(kicad_sch (version 20230121) (generator eeschema)

  (paper "A3")

  (title_block
    (title "Thunderbolt PCIe Adaper")
    (date "2024-07-09")
    (rev "1.0.3")
    (comment 1 "www.antmicro.com")
    (comment 2 "Antmicro Ltd.")
  )

  (junction (at 365.76 59.69) (diameter 0) (color 0 0 0 0)
  )
  (junction (at 175.26 43.18) (diameter 0) (color 0 0 0 0)
  )
  (junction (at 29.21 73.66) (diameter 0) (color 0 0 0 0)
  )
  (junction (at 83.82 207.01) (diameter 0) (color 0 0 0 0)
  )
  (junction (at 180.34 214.63) (diameter 0) (color 0 0 0 0)
  )
  (junction (at 339.09 67.31) (diameter 0) (color 0 0 0 0)
  )
  (junction (at 62.23 81.28) (diameter 0) (color 0 0 0 0)
  )
  (junction (at 374.65 146.05) (diameter 0) (color 0 0 0 0)
  )
  (junction (at 247.65 62.23) (diameter 0) (color 0 0 0 0)
  )
  (junction (at 62.23 83.82) (diameter 0) (color 0 0 0 0)
  )
  (junction (at 358.14 59.69) (diameter 0) (color 0 0 0 0)
  )
  (junction (at 190.5 212.09) (diameter 0) (color 0 0 0 0)
  )
  (junction (at 166.37 214.63) (diameter 0) (color 0 0 0 0)
  )
  (junction (at 375.92 48.26) (diameter 0) (color 0 0 0 0)
  )
  (junction (at 363.22 146.05) (diameter 0) (color 0 0 0 0)
  )
  (junction (at 247.65 212.09) (diameter 0) (color 0 0 0 0)
  )
  (junction (at 176.53 237.49) (diameter 0) (color 0 0 0 0)
  )
  (junction (at 29.21 57.15) (diameter 0) (color 0 0 0 0)
  )
  (junction (at 158.75 73.66) (diameter 0) (color 0 0 0 0)
  )
  (junction (at 135.89 219.71) (diameter 0) (color 0 0 0 0)
  )
  (junction (at 330.2 67.31) (diameter 0) (color 0 0 0 0)
  )
  (junction (at 49.53 260.35) (diameter 0) (color 0 0 0 0)
  )
  (junction (at 179.07 43.18) (diameter 0) (color 0 0 0 0)
  )
  (junction (at 60.96 152.4) (diameter 0) (color 0 0 0 0)
  )
  (junction (at 274.32 212.09) (diameter 0) (color 0 0 0 0)
  )
  (junction (at 60.96 149.86) (diameter 0) (color 0 0 0 0)
  )
  (junction (at 104.14 214.63) (diameter 0) (color 0 0 0 0)
  )
  (junction (at 259.08 146.05) (diameter 0) (color 0 0 0 0)
  )
  (junction (at 73.66 134.62) (diameter 0) (color 0 0 0 0)
  )
  (junction (at 60.96 242.57) (diameter 0) (color 0 0 0 0)
  )
  (junction (at 135.89 217.17) (diameter 0) (color 0 0 0 0)
  )
  (junction (at 130.81 260.35) (diameter 0) (color 0 0 0 0)
  )
  (junction (at 45.72 99.06) (diameter 0) (color 0 0 0 0)
  )
  (junction (at 36.83 207.01) (diameter 0) (color 0 0 0 0)
  )
  (junction (at 165.1 260.35) (diameter 0) (color 0 0 0 0)
  )
  (junction (at 228.6 212.09) (diameter 0) (color 0 0 0 0)
  )
  (junction (at 166.37 73.66) (diameter 0) (color 0 0 0 0)
  )
  (junction (at 193.04 212.09) (diameter 0) (color 0 0 0 0)
  )
  (junction (at 358.14 161.29) (diameter 0) (color 0 0 0 0)
  )
  (junction (at 262.89 43.18) (diameter 0) (color 0 0 0 0)
  )
  (junction (at 73.66 63.5) (diameter 0) (color 0 0 0 0)
  )
  (junction (at 292.1 146.05) (diameter 0) (color 0 0 0 0)
  )
  (junction (at 270.51 212.09) (diameter 0) (color 0 0 0 0)
  )
  (junction (at 287.02 74.93) (diameter 0) (color 0 0 0 0)
  )
  (junction (at 63.5 106.68) (diameter 0) (color 0 0 0 0)
  )
  (junction (at 53.34 207.01) (diameter 0) (color 0 0 0 0)
  )
  (junction (at 63.5 207.01) (diameter 0) (color 0 0 0 0)
  )
  (junction (at 184.15 71.12) (diameter 0) (color 0 0 0 0)
  )
  (junction (at 210.82 212.09) (diameter 0) (color 0 0 0 0)
  )
  (junction (at 73.66 48.26) (diameter 0) (color 0 0 0 0)
  )
  (junction (at 331.47 146.05) (diameter 0) (color 0 0 0 0)
  )
  (junction (at 375.92 59.69) (diameter 0) (color 0 0 0 0)
  )
  (junction (at 176.53 71.12) (diameter 0) (color 0 0 0 0)
  )
  (junction (at 288.29 43.18) (diameter 0) (color 0 0 0 0)
  )
  (junction (at 138.43 207.01) (diameter 0) (color 0 0 0 0)
  )
  (junction (at 241.3 212.09) (diameter 0) (color 0 0 0 0)
  )
  (junction (at 41.91 68.58) (diameter 0) (color 0 0 0 0)
  )
  (junction (at 201.93 212.09) (diameter 0) (color 0 0 0 0)
  )
  (junction (at 72.39 27.94) (diameter 0) (color 0 0 0 0)
  )
  (junction (at 134.62 111.76) (diameter 0) (color 0 0 0 0)
  )
  (junction (at 73.66 207.01) (diameter 0) (color 0 0 0 0)
  )
  (junction (at 224.79 43.18) (diameter 0) (color 0 0 0 0)
  )
  (junction (at 73.66 58.42) (diameter 0) (color 0 0 0 0)
  )
  (junction (at 35.56 57.15) (diameter 0) (color 0 0 0 0)
  )
  (junction (at 251.46 146.05) (diameter 0) (color 0 0 0 0)
  )
  (junction (at 66.04 48.26) (diameter 0) (color 0 0 0 0)
  )
  (junction (at 283.21 146.05) (diameter 0) (color 0 0 0 0)
  )
  (junction (at 219.71 212.09) (diameter 0) (color 0 0 0 0)
  )
  (junction (at 247.65 43.18) (diameter 0) (color 0 0 0 0)
  )
  (junction (at 339.09 146.05) (diameter 0) (color 0 0 0 0)
  )
  (junction (at 35.56 71.12) (diameter 0) (color 0 0 0 0)
  )
  (junction (at 317.5 59.69) (diameter 0) (color 0 0 0 0)
  )
  (junction (at 339.09 59.69) (diameter 0) (color 0 0 0 0)
  )
  (junction (at 262.89 62.23) (diameter 0) (color 0 0 0 0)
  )
  (junction (at 130.81 250.19) (diameter 0) (color 0 0 0 0)
  )
  (junction (at 123.19 245.11) (diameter 0) (color 0 0 0 0)
  )
  (junction (at 278.13 161.29) (diameter 0) (color 0 0 0 0)
  )
  (junction (at 160.02 134.62) (diameter 0) (color 0 0 0 0)
  )
  (junction (at 93.98 207.01) (diameter 0) (color 0 0 0 0)
  )
  (junction (at 252.73 43.18) (diameter 0) (color 0 0 0 0)
  )
  (junction (at 264.16 212.09) (diameter 0) (color 0 0 0 0)
  )
  (junction (at 135.89 227.33) (diameter 0) (color 0 0 0 0)
  )
  (junction (at 134.62 81.28) (diameter 0) (color 0 0 0 0)
  )
  (junction (at 281.94 43.18) (diameter 0) (color 0 0 0 0)
  )
  (junction (at 134.62 109.22) (diameter 0) (color 0 0 0 0)
  )
  (junction (at 271.78 43.18) (diameter 0) (color 0 0 0 0)
  )
  (junction (at 330.2 59.69) (diameter 0) (color 0 0 0 0)
  )
  (junction (at 349.25 59.69) (diameter 0) (color 0 0 0 0)
  )
  (junction (at 104.14 207.01) (diameter 0) (color 0 0 0 0)
  )
  (junction (at 257.81 212.09) (diameter 0) (color 0 0 0 0)
  )
  (junction (at 176.53 245.11) (diameter 0) (color 0 0 0 0)
  )
  (junction (at 241.3 227.33) (diameter 0) (color 0 0 0 0)
  )
  (junction (at 134.62 114.3) (diameter 0) (color 0 0 0 0)
  )
  (junction (at 161.29 43.18) (diameter 0) (color 0 0 0 0)
  )
  (junction (at 123.19 247.65) (diameter 0) (color 0 0 0 0)
  )
  (junction (at 62.23 78.74) (diameter 0) (color 0 0 0 0)
  )
  (junction (at 147.32 121.92) (diameter 0) (color 0 0 0 0)
  )

  (no_connect (at 74.93 91.44))
  (no_connect (at 74.93 127))
  (no_connect (at 74.93 129.54))
  (no_connect (at 74.93 93.98))
  (no_connect (at 74.93 38.1))
  (no_connect (at 133.35 35.56))
  (no_connect (at 133.35 38.1))
  (no_connect (at 74.93 109.22))
  (no_connect (at 74.93 101.6))
  (no_connect (at 74.93 165.1))
  (no_connect (at 74.93 35.56))
  (no_connect (at 74.93 96.52))

  (wire (pts (xy 73.66 157.48) (xy 74.93 157.48))
    (stroke (width 0) (type default))
  )
  (wire (pts (xy 133.35 60.96) (xy 135.89 60.96))
    (stroke (width 0) (type default))
  )
  (wire (pts (xy 39.37 54.61) (xy 73.66 54.61))
    (stroke (width 0) (type default))
  )
  (wire (pts (xy 73.66 142.24) (xy 74.93 142.24))
    (stroke (width 0) (type default))
  )
  (wire (pts (xy 331.47 146.05) (xy 331.47 157.48))
    (stroke (width 0) (type default))
  )
  (wire (pts (xy 163.83 214.63) (xy 166.37 214.63))
    (stroke (width 0) (type default))
  )
  (wire (pts (xy 176.53 242.57) (xy 163.83 242.57))
    (stroke (width 0) (type default))
  )
  (wire (pts (xy 166.37 73.66) (xy 166.37 78.74))
    (stroke (width 0) (type default))
  )
  (wire (pts (xy 134.62 167.64) (xy 134.62 170.18))
    (stroke (width 0) (type default))
  )
  (wire (pts (xy 134.62 111.76) (xy 134.62 114.3))
    (stroke (width 0) (type default))
  )
  (wire (pts (xy 133.35 149.86) (xy 137.16 149.86))
    (stroke (width 0) (type default))
  )
  (wire (pts (xy 247.65 214.63) (xy 247.65 212.09))
    (stroke (width 0) (type default))
  )
  (wire (pts (xy 339.09 74.93) (xy 339.09 76.2))
    (stroke (width 0) (type default))
  )
  (wire (pts (xy 180.34 222.25) (xy 180.34 220.98))
    (stroke (width 0) (type default))
  )
  (wire (pts (xy 134.62 109.22) (xy 135.89 109.22))
    (stroke (width 0) (type default))
  )
  (wire (pts (xy 135.89 217.17) (xy 138.43 217.17))
    (stroke (width 0) (type default))
  )
  (wire (pts (xy 134.62 78.74) (xy 134.62 81.28))
    (stroke (width 0) (type default))
  )
  (wire (pts (xy 247.65 45.72) (xy 247.65 43.18))
    (stroke (width 0) (type default))
  )
  (wire (pts (xy 133.35 124.46) (xy 137.16 124.46))
    (stroke (width 0) (type default))
  )
  (wire (pts (xy 210.82 212.09) (xy 210.82 214.63))
    (stroke (width 0) (type default))
  )
  (wire (pts (xy 119.38 229.87) (xy 119.38 232.41))
    (stroke (width 0) (type default))
  )
  (wire (pts (xy 62.23 63.5) (xy 66.04 63.5))
    (stroke (width 0) (type default))
  )
  (wire (pts (xy 158.75 83.82) (xy 158.75 85.09))
    (stroke (width 0) (type default))
  )
  (wire (pts (xy 365.76 59.69) (xy 375.92 59.69))
    (stroke (width 0) (type default))
  )
  (wire (pts (xy 41.91 64.77) (xy 41.91 68.58))
    (stroke (width 0) (type default))
  )
  (wire (pts (xy 375.92 74.93) (xy 375.92 76.2))
    (stroke (width 0) (type default))
  )
  (wire (pts (xy 283.21 146.05) (xy 292.1 146.05))
    (stroke (width 0) (type default))
  )
  (wire (pts (xy 133.35 111.76) (xy 134.62 111.76))
    (stroke (width 0) (type default))
  )
  (wire (pts (xy 365.76 58.42) (xy 365.76 59.69))
    (stroke (width 0) (type default))
  )
  (wire (pts (xy 119.38 245.11) (xy 123.19 245.11))
    (stroke (width 0) (type default))
  )
  (wire (pts (xy 53.34 78.74) (xy 62.23 78.74))
    (stroke (width 0) (type default))
  )
  (wire (pts (xy 289.56 64.77) (xy 278.13 64.77))
    (stroke (width 0) (type default))
  )
  (wire (pts (xy 59.69 40.64) (xy 59.69 48.26))
    (stroke (width 0) (type default))
  )
  (wire (pts (xy 35.56 57.15) (xy 41.91 57.15))
    (stroke (width 0) (type default))
  )
  (wire (pts (xy 259.08 161.29) (xy 260.35 161.29))
    (stroke (width 0) (type default))
  )
  (wire (pts (xy 62.23 58.42) (xy 66.04 58.42))
    (stroke (width 0) (type default))
  )
  (wire (pts (xy 247.65 62.23) (xy 247.65 67.31))
    (stroke (width 0) (type default))
  )
  (wire (pts (xy 365.76 59.69) (xy 365.76 66.04))
    (stroke (width 0) (type default))
  )
  (wire (pts (xy 133.35 66.04) (xy 135.89 66.04))
    (stroke (width 0) (type default))
  )
  (wire (pts (xy 271.78 50.8) (xy 271.78 53.34))
    (stroke (width 0) (type default))
  )
  (wire (pts (xy 163.83 245.11) (xy 170.18 245.11))
    (stroke (width 0) (type default))
  )
  (wire (pts (xy 133.35 134.62) (xy 160.02 134.62))
    (stroke (width 0) (type default))
  )
  (wire (pts (xy 73.66 213.36) (xy 73.66 215.9))
    (stroke (width 0) (type default))
  )
  (wire (pts (xy 189.23 214.63) (xy 190.5 214.63))
    (stroke (width 0) (type default))
  )
  (wire (pts (xy 363.22 146.05) (xy 363.22 158.75))
    (stroke (width 0) (type default))
  )
  (wire (pts (xy 133.35 78.74) (xy 134.62 78.74))
    (stroke (width 0) (type default))
  )
  (wire (pts (xy 73.66 160.02) (xy 74.93 160.02))
    (stroke (width 0) (type default))
  )
  (wire (pts (xy 163.83 232.41) (xy 229.87 232.41))
    (stroke (width 0) (type default))
  )
  (wire (pts (xy 116.84 217.17) (xy 116.84 218.44))
    (stroke (width 0) (type default))
  )
  (wire (pts (xy 363.22 146.05) (xy 374.65 146.05))
    (stroke (width 0) (type default))
  )
  (wire (pts (xy 104.14 214.63) (xy 104.14 215.9))
    (stroke (width 0) (type default))
  )
  (wire (pts (xy 259.08 158.75) (xy 260.35 158.75))
    (stroke (width 0) (type default))
  )
  (wire (pts (xy 133.35 160.02) (xy 134.62 160.02))
    (stroke (width 0) (type default))
  )
  (wire (pts (xy 138.43 219.71) (xy 135.89 219.71))
    (stroke (width 0) (type default))
  )
  (wire (pts (xy 358.14 170.18) (xy 358.14 171.45))
    (stroke (width 0) (type default))
  )
  (wire (pts (xy 31.75 207.01) (xy 36.83 207.01))
    (stroke (width 0) (type default))
  )
  (wire (pts (xy 64.77 27.94) (xy 72.39 27.94))
    (stroke (width 0) (type default))
  )
  (wire (pts (xy 59.69 266.7) (xy 59.69 267.97))
    (stroke (width 0) (type default))
  )
  (wire (pts (xy 45.72 99.06) (xy 45.72 101.6))
    (stroke (width 0) (type default))
  )
  (wire (pts (xy 60.96 242.57) (xy 62.23 242.57))
    (stroke (width 0) (type default))
  )
  (wire (pts (xy 241.3 227.33) (xy 241.3 228.6))
    (stroke (width 0) (type default))
  )
  (wire (pts (xy 64.77 134.62) (xy 66.04 134.62))
    (stroke (width 0) (type default))
  )
  (wire (pts (xy 317.5 59.69) (xy 318.77 59.69))
    (stroke (width 0) (type default))
  )
  (wire (pts (xy 259.08 165.1) (xy 259.08 161.29))
    (stroke (width 0) (type default))
  )
  (wire (pts (xy 339.09 67.31) (xy 339.09 69.85))
    (stroke (width 0) (type default))
  )
  (wire (pts (xy 133.35 121.92) (xy 137.16 121.92))
    (stroke (width 0) (type default))
  )
  (wire (pts (xy 57.15 242.57) (xy 60.96 242.57))
    (stroke (width 0) (type default))
  )
  (wire (pts (xy 133.35 154.94) (xy 137.16 154.94))
    (stroke (width 0) (type default))
  )
  (wire (pts (xy 323.85 59.69) (xy 330.2 59.69))
    (stroke (width 0) (type default))
  )
  (wire (pts (xy 73.66 137.16) (xy 73.66 134.62))
    (stroke (width 0) (type default))
  )
  (wire (pts (xy 252.73 43.18) (xy 262.89 43.18))
    (stroke (width 0) (type default))
  )
  (wire (pts (xy 60.96 251.46) (xy 60.96 252.73))
    (stroke (width 0) (type default))
  )
  (wire (pts (xy 147.32 121.92) (xy 156.21 121.92))
    (stroke (width 0) (type default))
  )
  (wire (pts (xy 255.27 212.09) (xy 257.81 212.09))
    (stroke (width 0) (type default))
  )
  (wire (pts (xy 287.02 72.39) (xy 287.02 74.93))
    (stroke (width 0) (type default))
  )
  (wire (pts (xy 241.3 212.09) (xy 247.65 212.09))
    (stroke (width 0) (type default))
  )
  (wire (pts (xy 176.53 71.12) (xy 176.53 78.74))
    (stroke (width 0) (type default))
  )
  (wire (pts (xy 288.29 57.15) (xy 289.56 57.15))
    (stroke (width 0) (type default))
  )
  (wire (pts (xy 73.66 58.42) (xy 74.93 58.42))
    (stroke (width 0) (type default))
  )
  (wire (pts (xy 339.09 146.05) (xy 339.09 158.75))
    (stroke (width 0) (type default))
  )
  (wire (pts (xy 123.19 247.65) (xy 127 247.65))
    (stroke (width 0) (type default))
  )
  (wire (pts (xy 123.19 224.79) (xy 123.19 227.33))
    (stroke (width 0) (type default))
  )
  (wire (pts (xy 358.14 161.29) (xy 358.14 165.1))
    (stroke (width 0) (type default))
  )
  (wire (pts (xy 63.5 106.68) (xy 66.04 106.68))
    (stroke (width 0) (type default))
  )
  (wire (pts (xy 339.09 158.75) (xy 340.36 158.75))
    (stroke (width 0) (type default))
  )
  (wire (pts (xy 134.62 237.49) (xy 138.43 237.49))
    (stroke (width 0) (type default))
  )
  (wire (pts (xy 63.5 121.92) (xy 74.93 121.92))
    (stroke (width 0) (type default))
  )
  (wire (pts (xy 175.26 52.07) (xy 175.26 54.61))
    (stroke (width 0) (type default))
  )
  (wire (pts (xy 224.79 43.18) (xy 229.87 43.18))
    (stroke (width 0) (type default))
  )
  (wire (pts (xy 176.53 245.11) (xy 175.26 245.11))
    (stroke (width 0) (type default))
  )
  (wire (pts (xy 73.66 58.42) (xy 73.66 63.5))
    (stroke (width 0) (type default))
  )
  (wire (pts (xy 247.65 72.39) (xy 247.65 76.2))
    (stroke (width 0) (type default))
  )
  (wire (pts (xy 262.89 43.18) (xy 262.89 45.72))
    (stroke (width 0) (type default))
  )
  (wire (pts (xy 330.2 66.04) (xy 330.2 67.31))
    (stroke (width 0) (type default))
  )
  (wire (pts (xy 52.07 43.18) (xy 52.07 40.64))
    (stroke (width 0) (type default))
  )
  (wire (pts (xy 270.51 222.25) (xy 270.51 224.79))
    (stroke (width 0) (type default))
  )
  (wire (pts (xy 133.35 71.12) (xy 176.53 71.12))
    (stroke (width 0) (type default))
  )
  (wire (pts (xy 58.42 144.78) (xy 60.96 144.78))
    (stroke (width 0) (type default))
  )
  (wire (pts (xy 247.65 43.18) (xy 252.73 43.18))
    (stroke (width 0) (type default))
  )
  (wire (pts (xy 72.39 26.67) (xy 72.39 27.94))
    (stroke (width 0) (type default))
  )
  (wire (pts (xy 27.94 57.15) (xy 29.21 57.15))
    (stroke (width 0) (type default))
  )
  (wire (pts (xy 72.39 43.18) (xy 74.93 43.18))
    (stroke (width 0) (type default))
  )
  (wire (pts (xy 190.5 212.09) (xy 190.5 214.63))
    (stroke (width 0) (type default))
  )
  (wire (pts (xy 60.96 152.4) (xy 60.96 157.48))
    (stroke (width 0) (type default))
  )
  (wire (pts (xy 274.32 212.09) (xy 278.13 212.09))
    (stroke (width 0) (type default))
  )
  (wire (pts (xy 140.97 66.04) (xy 142.24 66.04))
    (stroke (width 0) (type default))
  )
  (wire (pts (xy 264.16 212.09) (xy 270.51 212.09))
    (stroke (width 0) (type default))
  )
  (wire (pts (xy 119.38 229.87) (xy 138.43 229.87))
    (stroke (width 0) (type default))
  )
  (wire (pts (xy 35.56 57.15) (xy 35.56 59.69))
    (stroke (width 0) (type default))
  )
  (wire (pts (xy 133.35 109.22) (xy 134.62 109.22))
    (stroke (width 0) (type default))
  )
  (wire (pts (xy 63.5 207.01) (xy 53.34 207.01))
    (stroke (width 0) (type default))
  )
  (wire (pts (xy 142.24 149.86) (xy 156.21 149.86))
    (stroke (width 0) (type default))
  )
  (wire (pts (xy 163.83 229.87) (xy 232.41 229.87))
    (stroke (width 0) (type default))
  )
  (wire (pts (xy 262.89 50.8) (xy 262.89 53.34))
    (stroke (width 0) (type default))
  )
  (wire (pts (xy 278.13 161.29) (xy 278.13 165.1))
    (stroke (width 0) (type default))
  )
  (wire (pts (xy 250.19 146.05) (xy 251.46 146.05))
    (stroke (width 0) (type default))
  )
  (wire (pts (xy 278.13 170.18) (xy 278.13 171.45))
    (stroke (width 0) (type default))
  )
  (wire (pts (xy 163.83 212.09) (xy 190.5 212.09))
    (stroke (width 0) (type default))
  )
  (wire (pts (xy 134.62 109.22) (xy 134.62 111.76))
    (stroke (width 0) (type default))
  )
  (wire (pts (xy 124.46 217.17) (xy 135.89 217.17))
    (stroke (width 0) (type default))
  )
  (wire (pts (xy 63.5 116.84) (xy 74.93 116.84))
    (stroke (width 0) (type default))
  )
  (wire (pts (xy 133.35 55.88) (xy 135.89 55.88))
    (stroke (width 0) (type default))
  )
  (wire (pts (xy 62.23 83.82) (xy 66.04 83.82))
    (stroke (width 0) (type default))
  )
  (wire (pts (xy 358.14 71.12) (xy 358.14 76.2))
    (stroke (width 0) (type default))
  )
  (wire (pts (xy 307.34 59.69) (xy 317.5 59.69))
    (stroke (width 0) (type default))
  )
  (wire (pts (xy 229.87 243.84) (xy 257.81 243.84))
    (stroke (width 0) (type default))
  )
  (wire (pts (xy 48.26 207.01) (xy 53.34 207.01))
    (stroke (width 0) (type default))
  )
  (wire (pts (xy 176.53 237.49) (xy 175.26 237.49))
    (stroke (width 0) (type default))
  )
  (wire (pts (xy 330.2 146.05) (xy 331.47 146.05))
    (stroke (width 0) (type default))
  )
  (wire (pts (xy 201.93 212.09) (xy 201.93 214.63))
    (stroke (width 0) (type default))
  )
  (wire (pts (xy 262.89 72.39) (xy 262.89 76.2))
    (stroke (width 0) (type default))
  )
  (wire (pts (xy 133.35 73.66) (xy 158.75 73.66))
    (stroke (width 0) (type default))
  )
  (wire (pts (xy 93.98 213.36) (xy 93.98 215.9))
    (stroke (width 0) (type default))
  )
  (wire (pts (xy 59.69 234.95) (xy 68.58 234.95))
    (stroke (width 0) (type default))
  )
  (wire (pts (xy 247.65 241.3) (xy 247.65 220.98))
    (stroke (width 0) (type default))
  )
  (wire (pts (xy 73.66 53.34) (xy 74.93 53.34))
    (stroke (width 0) (type default))
  )
  (wire (pts (xy 257.81 212.09) (xy 264.16 212.09))
    (stroke (width 0) (type default))
  )
  (wire (pts (xy 170.18 237.49) (xy 163.83 237.49))
    (stroke (width 0) (type default))
  )
  (wire (pts (xy 135.89 226.06) (xy 135.89 227.33))
    (stroke (width 0) (type default))
  )
  (wire (pts (xy 134.62 81.28) (xy 135.89 81.28))
    (stroke (width 0) (type default))
  )
  (wire (pts (xy 29.21 57.15) (xy 29.21 59.69))
    (stroke (width 0) (type default))
  )
  (wire (pts (xy 62.23 81.28) (xy 62.23 78.74))
    (stroke (width 0) (type default))
  )
  (wire (pts (xy 224.79 41.91) (xy 224.79 43.18))
    (stroke (width 0) (type default))
  )
  (wire (pts (xy 142.24 129.54) (xy 146.05 129.54))
    (stroke (width 0) (type default))
  )
  (wire (pts (xy 375.92 59.69) (xy 375.92 57.15))
    (stroke (width 0) (type default))
  )
  (wire (pts (xy 130.81 257.81) (xy 130.81 260.35))
    (stroke (width 0) (type default))
  )
  (wire (pts (xy 375.92 52.07) (xy 375.92 48.26))
    (stroke (width 0) (type default))
  )
  (wire (pts (xy 339.09 165.1) (xy 339.09 161.29))
    (stroke (width 0) (type default))
  )
  (wire (pts (xy 130.81 266.7) (xy 130.81 267.97))
    (stroke (width 0) (type default))
  )
  (wire (pts (xy 140.97 55.88) (xy 142.24 55.88))
    (stroke (width 0) (type default))
  )
  (wire (pts (xy 160.02 134.62) (xy 170.18 134.62))
    (stroke (width 0) (type default))
  )
  (wire (pts (xy 278.13 64.77) (xy 278.13 67.31))
    (stroke (width 0) (type default))
  )
  (wire (pts (xy 160.02 118.11) (xy 160.02 127))
    (stroke (width 0) (type default))
  )
  (wire (pts (xy 123.19 250.19) (xy 123.19 247.65))
    (stroke (width 0) (type default))
  )
  (wire (pts (xy 270.51 212.09) (xy 270.51 217.17))
    (stroke (width 0) (type default))
  )
  (wire (pts (xy 116.84 217.17) (xy 119.38 217.17))
    (stroke (width 0) (type default))
  )
  (wire (pts (xy 219.71 212.09) (xy 219.71 214.63))
    (stroke (width 0) (type default))
  )
  (wire (pts (xy 313.69 57.15) (xy 317.5 57.15))
    (stroke (width 0) (type default))
  )
  (wire (pts (xy 142.24 144.78) (xy 146.05 144.78))
    (stroke (width 0) (type default))
  )
  (wire (pts (xy 175.26 43.18) (xy 179.07 43.18))
    (stroke (width 0) (type default))
  )
  (wire (pts (xy 271.78 43.18) (xy 281.94 43.18))
    (stroke (width 0) (type default))
  )
  (wire (pts (xy 257.81 220.98) (xy 257.81 243.84))
    (stroke (width 0) (type default))
  )
  (wire (pts (xy 73.66 134.62) (xy 74.93 134.62))
    (stroke (width 0) (type default))
  )
  (wire (pts (xy 375.92 67.31) (xy 375.92 69.85))
    (stroke (width 0) (type default))
  )
  (wire (pts (xy 142.24 124.46) (xy 147.32 124.46))
    (stroke (width 0) (type default))
  )
  (wire (pts (xy 358.14 59.69) (xy 358.14 66.04))
    (stroke (width 0) (type default))
  )
  (wire (pts (xy 36.83 207.01) (xy 43.18 207.01))
    (stroke (width 0) (type default))
  )
  (wire (pts (xy 63.5 104.14) (xy 66.04 104.14))
    (stroke (width 0) (type default))
  )
  (wire (pts (xy 252.73 43.18) (xy 252.73 45.72))
    (stroke (width 0) (type default))
  )
  (wire (pts (xy 375.92 59.69) (xy 375.92 62.23))
    (stroke (width 0) (type default))
  )
  (wire (pts (xy 71.12 104.14) (xy 74.93 104.14))
    (stroke (width 0) (type default))
  )
  (wire (pts (xy 36.83 214.63) (xy 36.83 215.9))
    (stroke (width 0) (type default))
  )
  (wire (pts (xy 59.69 260.35) (xy 59.69 261.62))
    (stroke (width 0) (type default))
  )
  (wire (pts (xy 130.81 250.19) (xy 138.43 250.19))
    (stroke (width 0) (type default))
  )
  (wire (pts (xy 133.35 144.78) (xy 137.16 144.78))
    (stroke (width 0) (type default))
  )
  (wire (pts (xy 374.65 146.05) (xy 381 146.05))
    (stroke (width 0) (type default))
  )
  (wire (pts (xy 29.21 64.77) (xy 29.21 73.66))
    (stroke (width 0) (type default))
  )
  (wire (pts (xy 71.12 99.06) (xy 74.93 99.06))
    (stroke (width 0) (type default))
  )
  (wire (pts (xy 224.79 43.18) (xy 224.79 45.72))
    (stroke (width 0) (type default))
  )
  (wire (pts (xy 247.65 62.23) (xy 262.89 62.23))
    (stroke (width 0) (type default))
  )
  (wire (pts (xy 193.04 212.09) (xy 201.93 212.09))
    (stroke (width 0) (type default))
  )
  (wire (pts (xy 287.02 74.93) (xy 289.56 74.93))
    (stroke (width 0) (type default))
  )
  (wire (pts (xy 331.47 162.56) (xy 331.47 165.1))
    (stroke (width 0) (type default))
  )
  (wire (pts (xy 138.43 212.09) (xy 138.43 207.01))
    (stroke (width 0) (type default))
  )
  (wire (pts (xy 48.26 242.57) (xy 52.07 242.57))
    (stroke (width 0) (type default))
  )
  (wire (pts (xy 93.98 207.01) (xy 83.82 207.01))
    (stroke (width 0) (type default))
  )
  (wire (pts (xy 123.19 245.11) (xy 123.19 247.65))
    (stroke (width 0) (type default))
  )
  (wire (pts (xy 63.5 114.3) (xy 74.93 114.3))
    (stroke (width 0) (type default))
  )
  (wire (pts (xy 232.41 229.87) (xy 232.41 241.3))
    (stroke (width 0) (type default))
  )
  (wire (pts (xy 158.75 73.66) (xy 158.75 78.74))
    (stroke (width 0) (type default))
  )
  (wire (pts (xy 232.41 241.3) (xy 247.65 241.3))
    (stroke (width 0) (type default))
  )
  (wire (pts (xy 339.09 66.04) (xy 339.09 67.31))
    (stroke (width 0) (type default))
  )
  (wire (pts (xy 375.92 48.26) (xy 384.81 48.26))
    (stroke (width 0) (type default))
  )
  (wire (pts (xy 83.82 207.01) (xy 83.82 208.28))
    (stroke (width 0) (type default))
  )
  (wire (pts (xy 41.91 68.58) (xy 74.93 68.58))
    (stroke (width 0) (type default))
  )
  (wire (pts (xy 63.5 207.01) (xy 63.5 208.28))
    (stroke (width 0) (type default))
  )
  (wire (pts (xy 130.81 252.73) (xy 130.81 250.19))
    (stroke (width 0) (type default))
  )
  (wire (pts (xy 71.12 134.62) (xy 73.66 134.62))
    (stroke (width 0) (type default))
  )
  (wire (pts (xy 49.53 266.7) (xy 49.53 267.97))
    (stroke (width 0) (type default))
  )
  (wire (pts (xy 135.89 219.71) (xy 135.89 220.98))
    (stroke (width 0) (type default))
  )
  (wire (pts (xy 325.12 72.39) (xy 313.69 72.39))
    (stroke (width 0) (type default))
  )
  (wire (pts (xy 132.08 245.11) (xy 138.43 245.11))
    (stroke (width 0) (type default))
  )
  (wire (pts (xy 132.08 247.65) (xy 138.43 247.65))
    (stroke (width 0) (type default))
  )
  (wire (pts (xy 130.81 260.35) (xy 130.81 261.62))
    (stroke (width 0) (type default))
  )
  (wire (pts (xy 71.12 83.82) (xy 74.93 83.82))
    (stroke (width 0) (type default))
  )
  (wire (pts (xy 73.66 48.26) (xy 74.93 48.26))
    (stroke (width 0) (type default))
  )
  (wire (pts (xy 140.97 45.72) (xy 142.24 45.72))
    (stroke (width 0) (type default))
  )
  (wire (pts (xy 62.23 88.9) (xy 66.04 88.9))
    (stroke (width 0) (type default))
  )
  (wire (pts (xy 133.35 129.54) (xy 137.16 129.54))
    (stroke (width 0) (type default))
  )
  (wire (pts (xy 176.53 240.03) (xy 176.53 237.49))
    (stroke (width 0) (type default))
  )
  (wire (pts (xy 175.26 43.18) (xy 175.26 46.99))
    (stroke (width 0) (type default))
  )
  (wire (pts (xy 161.29 52.07) (xy 161.29 54.61))
    (stroke (width 0) (type default))
  )
  (wire (pts (xy 330.2 59.69) (xy 330.2 60.96))
    (stroke (width 0) (type default))
  )
  (wire (pts (xy 210.82 219.71) (xy 210.82 220.98))
    (stroke (width 0) (type default))
  )
  (wire (pts (xy 219.71 219.71) (xy 219.71 220.98))
    (stroke (width 0) (type default))
  )
  (wire (pts (xy 276.86 158.75) (xy 283.21 158.75))
    (stroke (width 0) (type default))
  )
  (wire (pts (xy 287.02 74.93) (xy 287.02 76.2))
    (stroke (width 0) (type default))
  )
  (wire (pts (xy 175.26 254) (xy 175.26 252.73))
    (stroke (width 0) (type default))
  )
  (wire (pts (xy 133.35 86.36) (xy 142.24 86.36))
    (stroke (width 0) (type default))
  )
  (wire (pts (xy 49.53 257.81) (xy 49.53 260.35))
    (stroke (width 0) (type default))
  )
  (wire (pts (xy 251.46 162.56) (xy 251.46 165.1))
    (stroke (width 0) (type default))
  )
  (wire (pts (xy 166.37 73.66) (xy 189.23 73.66))
    (stroke (width 0) (type default))
  )
  (wire (pts (xy 27.94 73.66) (xy 29.21 73.66))
    (stroke (width 0) (type default))
  )
  (wire (pts (xy 160.02 132.08) (xy 160.02 134.62))
    (stroke (width 0) (type default))
  )
  (wire (pts (xy 228.6 219.71) (xy 228.6 220.98))
    (stroke (width 0) (type default))
  )
  (wire (pts (xy 259.08 170.18) (xy 259.08 171.45))
    (stroke (width 0) (type default))
  )
  (wire (pts (xy 163.83 260.35) (xy 165.1 260.35))
    (stroke (width 0) (type default))
  )
  (wire (pts (xy 193.04 219.71) (xy 193.04 220.98))
    (stroke (width 0) (type default))
  )
  (wire (pts (xy 271.78 43.18) (xy 271.78 45.72))
    (stroke (width 0) (type default))
  )
  (wire (pts (xy 257.81 214.63) (xy 257.81 212.09))
    (stroke (width 0) (type default))
  )
  (wire (pts (xy 60.96 157.48) (xy 58.42 157.48))
    (stroke (width 0) (type default))
  )
  (wire (pts (xy 36.83 207.01) (xy 36.83 209.55))
    (stroke (width 0) (type default))
  )
  (wire (pts (xy 60.96 242.57) (xy 60.96 246.38))
    (stroke (width 0) (type default))
  )
  (wire (pts (xy 93.98 207.01) (xy 93.98 208.28))
    (stroke (width 0) (type default))
  )
  (wire (pts (xy 63.5 119.38) (xy 74.93 119.38))
    (stroke (width 0) (type default))
  )
  (wire (pts (xy 146.05 50.8) (xy 148.59 50.8))
    (stroke (width 0) (type default))
  )
  (wire (pts (xy 73.66 54.61) (xy 73.66 58.42))
    (stroke (width 0) (type default))
  )
  (wire (pts (xy 41.91 57.15) (xy 41.91 59.69))
    (stroke (width 0) (type default))
  )
  (wire (pts (xy 93.98 207.01) (xy 104.14 207.01))
    (stroke (width 0) (type default))
  )
  (wire (pts (xy 119.38 254) (xy 119.38 252.73))
    (stroke (width 0) (type default))
  )
  (wire (pts (xy 134.62 234.95) (xy 138.43 234.95))
    (stroke (width 0) (type default))
  )
  (wire (pts (xy 64.77 30.48) (xy 64.77 27.94))
    (stroke (width 0) (type default))
  )
  (wire (pts (xy 53.34 207.01) (xy 53.34 208.28))
    (stroke (width 0) (type default))
  )
  (wire (pts (xy 29.21 73.66) (xy 74.93 73.66))
    (stroke (width 0) (type default))
  )
  (wire (pts (xy 59.69 48.26) (xy 66.04 48.26))
    (stroke (width 0) (type default))
  )
  (wire (pts (xy 71.12 106.68) (xy 74.93 106.68))
    (stroke (width 0) (type default))
  )
  (wire (pts (xy 62.23 83.82) (xy 62.23 88.9))
    (stroke (width 0) (type default))
  )
  (wire (pts (xy 74.93 137.16) (xy 73.66 137.16))
    (stroke (width 0) (type default))
  )
  (wire (pts (xy 339.09 146.05) (xy 349.25 146.05))
    (stroke (width 0) (type default))
  )
  (wire (pts (xy 158.75 73.66) (xy 166.37 73.66))
    (stroke (width 0) (type default))
  )
  (wire (pts (xy 330.2 67.31) (xy 339.09 67.31))
    (stroke (width 0) (type default))
  )
  (wire (pts (xy 349.25 71.12) (xy 349.25 76.2))
    (stroke (width 0) (type default))
  )
  (wire (pts (xy 214.63 43.18) (xy 224.79 43.18))
    (stroke (width 0) (type default))
  )
  (wire (pts (xy 142.24 121.92) (xy 147.32 121.92))
    (stroke (width 0) (type default))
  )
  (wire (pts (xy 176.53 242.57) (xy 176.53 245.11))
    (stroke (width 0) (type default))
  )
  (wire (pts (xy 176.53 240.03) (xy 163.83 240.03))
    (stroke (width 0) (type default))
  )
  (wire (pts (xy 147.32 121.92) (xy 147.32 124.46))
    (stroke (width 0) (type default))
  )
  (wire (pts (xy 361.95 146.05) (xy 363.22 146.05))
    (stroke (width 0) (type default))
  )
  (wire (pts (xy 292.1 146.05) (xy 293.37 146.05))
    (stroke (width 0) (type default))
  )
  (wire (pts (xy 166.37 214.63) (xy 180.34 214.63))
    (stroke (width 0) (type default))
  )
  (wire (pts (xy 68.58 247.65) (xy 68.58 252.73))
    (stroke (width 0) (type default))
  )
  (wire (pts (xy 55.88 149.86) (xy 60.96 149.86))
    (stroke (width 0) (type default))
  )
  (wire (pts (xy 63.5 207.01) (xy 73.66 207.01))
    (stroke (width 0) (type default))
  )
  (wire (pts (xy 234.95 43.18) (xy 247.65 43.18))
    (stroke (width 0) (type default))
  )
  (wire (pts (xy 134.62 160.02) (xy 134.62 162.56))
    (stroke (width 0) (type default))
  )
  (wire (pts (xy 133.35 96.52) (xy 142.24 96.52))
    (stroke (width 0) (type default))
  )
  (wire (pts (xy 52.07 40.64) (xy 59.69 40.64))
    (stroke (width 0) (type default))
  )
  (wire (pts (xy 180.34 265.43) (xy 180.34 266.7))
    (stroke (width 0) (type default))
  )
  (wire (pts (xy 123.19 227.33) (xy 135.89 227.33))
    (stroke (width 0) (type default))
  )
  (wire (pts (xy 365.76 71.12) (xy 365.76 76.2))
    (stroke (width 0) (type default))
  )
  (wire (pts (xy 228.6 212.09) (xy 228.6 214.63))
    (stroke (width 0) (type default))
  )
  (wire (pts (xy 179.07 243.84) (xy 179.07 245.11))
    (stroke (width 0) (type default))
  )
  (wire (pts (xy 180.34 214.63) (xy 184.15 214.63))
    (stroke (width 0) (type default))
  )
  (wire (pts (xy 185.42 43.18) (xy 189.23 43.18))
    (stroke (width 0) (type default))
  )
  (wire (pts (xy 134.62 240.03) (xy 138.43 240.03))
    (stroke (width 0) (type default))
  )
  (wire (pts (xy 278.13 153.67) (xy 278.13 161.29))
    (stroke (width 0) (type default))
  )
  (wire (pts (xy 29.21 57.15) (xy 35.56 57.15))
    (stroke (width 0) (type default))
  )
  (wire (pts (xy 27.94 68.58) (xy 41.91 68.58))
    (stroke (width 0) (type default))
  )
  (wire (pts (xy 228.6 212.09) (xy 241.3 212.09))
    (stroke (width 0) (type default))
  )
  (wire (pts (xy 49.53 260.35) (xy 49.53 261.62))
    (stroke (width 0) (type default))
  )
  (wire (pts (xy 339.09 161.29) (xy 340.36 161.29))
    (stroke (width 0) (type default))
  )
  (wire (pts (xy 27.94 71.12) (xy 35.56 71.12))
    (stroke (width 0) (type default))
  )
  (wire (pts (xy 375.92 46.99) (xy 375.92 48.26))
    (stroke (width 0) (type default))
  )
  (wire (pts (xy 176.53 83.82) (xy 176.53 85.09))
    (stroke (width 0) (type default))
  )
  (wire (pts (xy 331.47 146.05) (xy 339.09 146.05))
    (stroke (width 0) (type default))
  )
  (wire (pts (xy 40.64 99.06) (xy 45.72 99.06))
    (stroke (width 0) (type default))
  )
  (wire (pts (xy 135.89 227.33) (xy 138.43 227.33))
    (stroke (width 0) (type default))
  )
  (wire (pts (xy 276.86 161.29) (xy 278.13 161.29))
    (stroke (width 0) (type default))
  )
  (wire (pts (xy 72.39 27.94) (xy 72.39 43.18))
    (stroke (width 0) (type default))
  )
  (wire (pts (xy 210.82 212.09) (xy 219.71 212.09))
    (stroke (width 0) (type default))
  )
  (wire (pts (xy 104.14 220.98) (xy 104.14 222.25))
    (stroke (width 0) (type default))
  )
  (wire (pts (xy 262.89 41.91) (xy 262.89 43.18))
    (stroke (width 0) (type default))
  )
  (wire (pts (xy 356.87 161.29) (xy 358.14 161.29))
    (stroke (width 0) (type default))
  )
  (wire (pts (xy 62.23 83.82) (xy 62.23 81.28))
    (stroke (width 0) (type default))
  )
  (wire (pts (xy 60.96 144.78) (xy 60.96 149.86))
    (stroke (width 0) (type default))
  )
  (wire (pts (xy 307.34 67.31) (xy 330.2 67.31))
    (stroke (width 0) (type default))
  )
  (wire (pts (xy 55.88 152.4) (xy 60.96 152.4))
    (stroke (width 0) (type default))
  )
  (wire (pts (xy 38.1 152.4) (xy 50.8 152.4))
    (stroke (width 0) (type default))
  )
  (wire (pts (xy 133.35 50.8) (xy 140.97 50.8))
    (stroke (width 0) (type default))
  )
  (wire (pts (xy 175.26 259.08) (xy 175.26 266.7))
    (stroke (width 0) (type default))
  )
  (wire (pts (xy 252.73 50.8) (xy 252.73 53.34))
    (stroke (width 0) (type default))
  )
  (wire (pts (xy 247.65 212.09) (xy 250.19 212.09))
    (stroke (width 0) (type default))
  )
  (wire (pts (xy 73.66 207.01) (xy 73.66 208.28))
    (stroke (width 0) (type default))
  )
  (wire (pts (xy 176.53 71.12) (xy 184.15 71.12))
    (stroke (width 0) (type default))
  )
  (wire (pts (xy 298.45 146.05) (xy 299.72 146.05))
    (stroke (width 0) (type default))
  )
  (wire (pts (xy 133.35 114.3) (xy 134.62 114.3))
    (stroke (width 0) (type default))
  )
  (wire (pts (xy 83.82 207.01) (xy 73.66 207.01))
    (stroke (width 0) (type default))
  )
  (wire (pts (xy 288.29 43.18) (xy 288.29 57.15))
    (stroke (width 0) (type default))
  )
  (wire (pts (xy 130.81 250.19) (xy 123.19 250.19))
    (stroke (width 0) (type default))
  )
  (wire (pts (xy 134.62 114.3) (xy 134.62 116.84))
    (stroke (width 0) (type default))
  )
  (wire (pts (xy 281.94 43.18) (xy 288.29 43.18))
    (stroke (width 0) (type default))
  )
  (wire (pts (xy 45.72 99.06) (xy 66.04 99.06))
    (stroke (width 0) (type default))
  )
  (wire (pts (xy 219.71 212.09) (xy 228.6 212.09))
    (stroke (width 0) (type default))
  )
  (wire (pts (xy 104.14 213.36) (xy 104.14 214.63))
    (stroke (width 0) (type default))
  )
  (wire (pts (xy 163.83 227.33) (xy 241.3 227.33))
    (stroke (width 0) (type default))
  )
  (wire (pts (xy 74.93 63.5) (xy 73.66 63.5))
    (stroke (width 0) (type default))
  )
  (wire (pts (xy 138.43 205.74) (xy 138.43 207.01))
    (stroke (width 0) (type default))
  )
  (wire (pts (xy 180.34 259.08) (xy 180.34 260.35))
    (stroke (width 0) (type default))
  )
  (wire (pts (xy 201.93 212.09) (xy 210.82 212.09))
    (stroke (width 0) (type default))
  )
  (wire (pts (xy 307.34 57.15) (xy 308.61 57.15))
    (stroke (width 0) (type default))
  )
  (wire (pts (xy 193.04 212.09) (xy 193.04 214.63))
    (stroke (width 0) (type default))
  )
  (wire (pts (xy 281.94 43.18) (xy 281.94 45.72))
    (stroke (width 0) (type default))
  )
  (wire (pts (xy 241.3 212.09) (xy 241.3 220.98))
    (stroke (width 0) (type default))
  )
  (wire (pts (xy 133.35 93.98) (xy 142.24 93.98))
    (stroke (width 0) (type default))
  )
  (wire (pts (xy 251.46 146.05) (xy 251.46 157.48))
    (stroke (width 0) (type default))
  )
  (wire (pts (xy 274.32 210.82) (xy 274.32 212.09))
    (stroke (width 0) (type default))
  )
  (wire (pts (xy 165.1 260.35) (xy 165.1 266.7))
    (stroke (width 0) (type default))
  )
  (wire (pts (xy 140.97 60.96) (xy 142.24 60.96))
    (stroke (width 0) (type default))
  )
  (wire (pts (xy 138.43 260.35) (xy 130.81 260.35))
    (stroke (width 0) (type default))
  )
  (wire (pts (xy 317.5 57.15) (xy 317.5 59.69))
    (stroke (width 0) (type default))
  )
  (wire (pts (xy 71.12 58.42) (xy 73.66 58.42))
    (stroke (width 0) (type default))
  )
  (wire (pts (xy 133.35 101.6) (xy 142.24 101.6))
    (stroke (width 0) (type default))
  )
  (wire (pts (xy 251.46 146.05) (xy 259.08 146.05))
    (stroke (width 0) (type default))
  )
  (wire (pts (xy 142.24 139.7) (xy 146.05 139.7))
    (stroke (width 0) (type default))
  )
  (wire (pts (xy 163.83 250.19) (xy 180.34 250.19))
    (stroke (width 0) (type default))
  )
  (wire (pts (xy 104.14 207.01) (xy 138.43 207.01))
    (stroke (width 0) (type default))
  )
  (wire (pts (xy 349.25 59.69) (xy 358.14 59.69))
    (stroke (width 0) (type default))
  )
  (wire (pts (xy 358.14 153.67) (xy 358.14 161.29))
    (stroke (width 0) (type default))
  )
  (wire (pts (xy 259.08 146.05) (xy 259.08 158.75))
    (stroke (width 0) (type default))
  )
  (wire (pts (xy 161.29 43.18) (xy 175.26 43.18))
    (stroke (width 0) (type default))
  )
  (wire (pts (xy 339.09 59.69) (xy 349.25 59.69))
    (stroke (width 0) (type default))
  )
  (wire (pts (xy 45.72 106.68) (xy 45.72 109.22))
    (stroke (width 0) (type default))
  )
  (wire (pts (xy 180.34 215.9) (xy 180.34 214.63))
    (stroke (width 0) (type default))
  )
  (wire (pts (xy 63.5 104.14) (xy 63.5 106.68))
    (stroke (width 0) (type default))
  )
  (wire (pts (xy 262.89 43.18) (xy 271.78 43.18))
    (stroke (width 0) (type default))
  )
  (wire (pts (xy 49.53 260.35) (xy 59.69 260.35))
    (stroke (width 0) (type default))
  )
  (wire (pts (xy 63.5 106.68) (xy 54.61 106.68))
    (stroke (width 0) (type default))
  )
  (wire (pts (xy 184.15 71.12) (xy 189.23 71.12))
    (stroke (width 0) (type default))
  )
  (wire (pts (xy 48.26 260.35) (xy 49.53 260.35))
    (stroke (width 0) (type default))
  )
  (wire (pts (xy 60.96 149.86) (xy 74.93 149.86))
    (stroke (width 0) (type default))
  )
  (wire (pts (xy 71.12 78.74) (xy 74.93 78.74))
    (stroke (width 0) (type default))
  )
  (wire (pts (xy 74.93 152.4) (xy 60.96 152.4))
    (stroke (width 0) (type default))
  )
  (wire (pts (xy 270.51 212.09) (xy 274.32 212.09))
    (stroke (width 0) (type default))
  )
  (wire (pts (xy 339.09 59.69) (xy 339.09 60.96))
    (stroke (width 0) (type default))
  )
  (wire (pts (xy 133.35 43.18) (xy 161.29 43.18))
    (stroke (width 0) (type default))
  )
  (wire (pts (xy 175.26 252.73) (xy 163.83 252.73))
    (stroke (width 0) (type default))
  )
  (wire (pts (xy 73.66 144.78) (xy 74.93 144.78))
    (stroke (width 0) (type default))
  )
  (wire (pts (xy 161.29 43.18) (xy 161.29 46.99))
    (stroke (width 0) (type default))
  )
  (wire (pts (xy 190.5 212.09) (xy 193.04 212.09))
    (stroke (width 0) (type default))
  )
  (wire (pts (xy 133.35 139.7) (xy 137.16 139.7))
    (stroke (width 0) (type default))
  )
  (wire (pts (xy 53.34 213.36) (xy 53.34 215.9))
    (stroke (width 0) (type default))
  )
  (wire (pts (xy 63.5 213.36) (xy 63.5 215.9))
    (stroke (width 0) (type default))
  )
  (wire (pts (xy 119.38 237.49) (xy 119.38 238.76))
    (stroke (width 0) (type default))
  )
  (wire (pts (xy 104.14 214.63) (xy 138.43 214.63))
    (stroke (width 0) (type default))
  )
  (wire (pts (xy 283.21 146.05) (xy 283.21 158.75))
    (stroke (width 0) (type default))
  )
  (wire (pts (xy 386.08 146.05) (xy 387.35 146.05))
    (stroke (width 0) (type default))
  )
  (wire (pts (xy 83.82 213.36) (xy 83.82 215.9))
    (stroke (width 0) (type default))
  )
  (wire (pts (xy 184.15 71.12) (xy 184.15 78.74))
    (stroke (width 0) (type default))
  )
  (wire (pts (xy 73.66 48.26) (xy 73.66 53.34))
    (stroke (width 0) (type default))
  )
  (wire (pts (xy 133.35 116.84) (xy 134.62 116.84))
    (stroke (width 0) (type default))
  )
  (wire (pts (xy 62.23 81.28) (xy 66.04 81.28))
    (stroke (width 0) (type default))
  )
  (wire (pts (xy 66.04 48.26) (xy 73.66 48.26))
    (stroke (width 0) (type default))
  )
  (wire (pts (xy 184.15 83.82) (xy 184.15 85.09))
    (stroke (width 0) (type default))
  )
  (wire (pts (xy 262.89 62.23) (xy 262.89 67.31))
    (stroke (width 0) (type default))
  )
  (wire (pts (xy 281.94 146.05) (xy 283.21 146.05))
    (stroke (width 0) (type default))
  )
  (wire (pts (xy 104.14 207.01) (xy 104.14 208.28))
    (stroke (width 0) (type default))
  )
  (wire (pts (xy 241.3 226.06) (xy 241.3 227.33))
    (stroke (width 0) (type default))
  )
  (wire (pts (xy 281.94 50.8) (xy 281.94 53.34))
    (stroke (width 0) (type default))
  )
  (wire (pts (xy 71.12 63.5) (xy 73.66 63.5))
    (stroke (width 0) (type default))
  )
  (wire (pts (xy 71.12 88.9) (xy 74.93 88.9))
    (stroke (width 0) (type default))
  )
  (wire (pts (xy 278.13 72.39) (xy 278.13 76.2))
    (stroke (width 0) (type default))
  )
  (wire (pts (xy 62.23 78.74) (xy 66.04 78.74))
    (stroke (width 0) (type default))
  )
  (wire (pts (xy 224.79 50.8) (xy 224.79 53.34))
    (stroke (width 0) (type default))
  )
  (wire (pts (xy 180.34 250.19) (xy 180.34 254))
    (stroke (width 0) (type default))
  )
  (wire (pts (xy 349.25 59.69) (xy 349.25 66.04))
    (stroke (width 0) (type default))
  )
  (wire (pts (xy 179.07 245.11) (xy 176.53 245.11))
    (stroke (width 0) (type default))
  )
  (wire (pts (xy 259.08 146.05) (xy 269.24 146.05))
    (stroke (width 0) (type default))
  )
  (wire (pts (xy 133.35 45.72) (xy 135.89 45.72))
    (stroke (width 0) (type default))
  )
  (wire (pts (xy 133.35 88.9) (xy 142.24 88.9))
    (stroke (width 0) (type default))
  )
  (wire (pts (xy 331.47 170.18) (xy 331.47 171.45))
    (stroke (width 0) (type default))
  )
  (wire (pts (xy 247.65 62.23) (xy 247.65 50.8))
    (stroke (width 0) (type default))
  )
  (wire (pts (xy 142.24 154.94) (xy 146.05 154.94))
    (stroke (width 0) (type default))
  )
  (wire (pts (xy 133.35 81.28) (xy 134.62 81.28))
    (stroke (width 0) (type default))
  )
  (wire (pts (xy 339.09 170.18) (xy 339.09 171.45))
    (stroke (width 0) (type default))
  )
  (wire (pts (xy 330.2 59.69) (xy 339.09 59.69))
    (stroke (width 0) (type default))
  )
  (wire (pts (xy 68.58 234.95) (xy 68.58 237.49))
    (stroke (width 0) (type default))
  )
  (wire (pts (xy 165.1 257.81) (xy 165.1 260.35))
    (stroke (width 0) (type default))
  )
  (wire (pts (xy 289.56 72.39) (xy 287.02 72.39))
    (stroke (width 0) (type default))
  )
  (wire (pts (xy 133.35 104.14) (xy 142.24 104.14))
    (stroke (width 0) (type default))
  )
  (wire (pts (xy 71.12 81.28) (xy 74.93 81.28))
    (stroke (width 0) (type default))
  )
  (wire (pts (xy 179.07 43.18) (xy 180.34 43.18))
    (stroke (width 0) (type default))
  )
  (wire (pts (xy 358.14 59.69) (xy 365.76 59.69))
    (stroke (width 0) (type default))
  )
  (wire (pts (xy 179.07 238.76) (xy 179.07 237.49))
    (stroke (width 0) (type default))
  )
  (wire (pts (xy 166.37 83.82) (xy 166.37 85.09))
    (stroke (width 0) (type default))
  )
  (wire (pts (xy 307.34 72.39) (xy 308.61 72.39))
    (stroke (width 0) (type default))
  )
  (wire (pts (xy 123.19 245.11) (xy 127 245.11))
    (stroke (width 0) (type default))
  )
  (wire (pts (xy 119.38 245.11) (xy 119.38 247.65))
    (stroke (width 0) (type default))
  )
  (wire (pts (xy 251.46 170.18) (xy 251.46 171.45))
    (stroke (width 0) (type default))
  )
  (wire (pts (xy 229.87 232.41) (xy 229.87 243.84))
    (stroke (width 0) (type default))
  )
  (wire (pts (xy 179.07 237.49) (xy 176.53 237.49))
    (stroke (width 0) (type default))
  )
  (wire (pts (xy 356.87 158.75) (xy 363.22 158.75))
    (stroke (width 0) (type default))
  )
  (wire (pts (xy 262.89 62.23) (xy 289.56 62.23))
    (stroke (width 0) (type default))
  )
  (wire (pts (xy 163.83 257.81) (xy 165.1 257.81))
    (stroke (width 0) (type default))
  )
  (wire (pts (xy 35.56 71.12) (xy 74.93 71.12))
    (stroke (width 0) (type default))
  )
  (wire (pts (xy 35.56 64.77) (xy 35.56 71.12))
    (stroke (width 0) (type default))
  )
  (wire (pts (xy 201.93 219.71) (xy 201.93 220.98))
    (stroke (width 0) (type default))
  )
  (wire (pts (xy 135.89 217.17) (xy 135.89 219.71))
    (stroke (width 0) (type default))
  )

  (text "R99 0R 22.4A PMR03EZPJ000" (at 370.205 157.48 0)
    (effects (font (size 1.27 1.27)) (justify left bottom))
  )
  (text "Ideal diodes" (at 298.45 130.175 0)
    (effects (font (size 2.54 2.54) bold) (justify left bottom))
  )
  (text "USB Power Delivery Controller" (at 77.47 18.415 0)
    (effects (font (size 2.54 2.54) bold) (justify left bottom))
  )
  (text "UVLO: 4.2V" (at 111.125 211.455 0)
    (effects (font (size 1.27 1.27)) (justify left bottom))
  )
  (text "12V Buck-Boost Converter" (at 121.285 192.405 0)
    (effects (font (size 2.54 2.54) bold) (justify left bottom))
  )
  (text "3V3 Buck Converter" (at 280.67 34.925 0)
    (effects (font (size 2.54 2.54) bold) (justify left bottom))
  )
  (text "R98 0R 22.4A PMR03EZPJ000" (at 285.75 156.845 0)
    (effects (font (size 1.27 1.27)) (justify left bottom))
  )

  (label "TPS_3V3" (at 133.35 50.8 0) (fields_autoplaced)
    (effects (font (size 1.27 1.27)) (justify left bottom))
  )
  (label "I_SENSE_P" (at 166.37 229.87 0) (fields_autoplaced)
    (effects (font (size 1.27 1.27)) (justify left bottom))
  )
  (label "TPS_3V3" (at 54.61 106.68 0) (fields_autoplaced)
    (effects (font (size 1.27 1.27)) (justify left bottom))
  )
  (label "TPS_3V3" (at 53.34 78.74 0) (fields_autoplaced)
    (effects (font (size 1.27 1.27)) (justify left bottom))
  )
  (label "TPS_3V3" (at 156.21 121.92 180) (fields_autoplaced)
    (effects (font (size 1.27 1.27)) (justify right bottom))
  )
  (label "I_SENSE_N" (at 176.53 232.41 180) (fields_autoplaced)
    (effects (font (size 1.27 1.27)) (justify right bottom))
  )
  (label "SMPS_LDO" (at 289.56 64.77 180) (fields_autoplaced)
    (effects (font (size 1.27 1.27)) (justify right bottom))
  )
  (label "TPS_3V3" (at 156.21 149.86 180) (fields_autoplaced)
    (effects (font (size 1.27 1.27)) (justify right bottom))
  )
  (label "DCDC_EN" (at 59.69 234.95 0) (fields_autoplaced)
    (effects (font (size 1.27 1.27)) (justify left bottom))
  )
  (label "TPS_3V3" (at 160.02 118.11 270) (fields_autoplaced)
    (effects (font (size 1.27 1.27)) (justify right bottom))
  )
  (label "DCDC_EN" (at 120.65 214.63 180) (fields_autoplaced)
    (effects (font (size 1.27 1.27)) (justify right bottom))
  )
  (label "SMPS_LDO" (at 325.12 72.39 180) (fields_autoplaced)
    (effects (font (size 1.27 1.27)) (justify right bottom))
  )
  (label "TPS_3V3" (at 38.1 152.4 0) (fields_autoplaced)
    (effects (font (size 1.27 1.27)) (justify left bottom))
  )

  (global_label "12V0_MOLEX" (shape input) (at 250.19 146.05 180) (fields_autoplaced)
    (effects (font (size 1.27 1.27)) (justify right))
    (property "Intersheetrefs" "${INTERSHEET_REFS}" (at 235.9236 146.1294 0)
      (effects (font (size 1.27 1.27)) (justify right) hide)
    )
  )
  (global_label "12V0_DCDC" (shape input) (at 330.2 146.05 180) (fields_autoplaced)
    (effects (font (size 1.27 1.27)) (justify right))
    (property "Intersheetrefs" "${INTERSHEET_REFS}" (at 317.0221 146.1294 0)
      (effects (font (size 1.27 1.27)) (justify right) hide)
    )
  )
  (global_label "SPI_MISO" (shape input) (at 63.5 119.38 180) (fields_autoplaced)
    (effects (font (size 1.27 1.27)) (justify right))
    (property "Intersheetrefs" "${INTERSHEET_REFS}" (at 52.4388 119.3006 0)
      (effects (font (size 1.27 1.27)) (justify right) hide)
    )
  )
  (global_label "12V0_MOLEX" (shape input) (at 48.26 260.35 180) (fields_autoplaced)
    (effects (font (size 1.27 1.27)) (justify right))
    (property "Intersheetrefs" "${INTERSHEET_REFS}" (at 33.9936 260.4294 0)
      (effects (font (size 1.27 1.27)) (justify right) hide)
    )
  )
  (global_label "3V3_SYS" (shape input) (at 27.94 57.15 180) (fields_autoplaced)
    (effects (font (size 1.27 1.27)) (justify right))
    (property "Intersheetrefs" "${INTERSHEET_REFS}" (at 17.544 57.2294 0)
      (effects (font (size 1.27 1.27)) (justify right) hide)
    )
  )
  (global_label "LSX_R2P" (shape input) (at 73.66 142.24 180) (fields_autoplaced)
    (effects (font (size 1.27 1.27)) (justify right))
    (property "Intersheetrefs" "${INTERSHEET_REFS}" (at 63.0826 142.1606 0)
      (effects (font (size 1.27 1.27)) (justify right) hide)
    )
  )
  (global_label "SPI_SCLK" (shape input) (at 63.5 114.3 180) (fields_autoplaced)
    (effects (font (size 1.27 1.27)) (justify right))
    (property "Intersheetrefs" "${INTERSHEET_REFS}" (at 52.2574 114.2206 0)
      (effects (font (size 1.27 1.27)) (justify right) hide)
    )
  )
  (global_label "SPI_CS" (shape output) (at 63.5 121.92 180) (fields_autoplaced)
    (effects (font (size 1.27 1.27)) (justify right))
    (property "Intersheetrefs" "${INTERSHEET_REFS}" (at 54.5555 121.8406 0)
      (effects (font (size 1.27 1.27)) (justify right) hide)
    )
  )
  (global_label "CC1" (shape input) (at 189.23 71.12 0) (fields_autoplaced)
    (effects (font (size 1.27 1.27)) (justify left))
    (property "Intersheetrefs" "${INTERSHEET_REFS}" (at 195.3926 71.0406 0)
      (effects (font (size 1.27 1.27)) (justify left) hide)
    )
  )
  (global_label "I2C1_IRQ" (shape input) (at 27.94 73.66 180) (fields_autoplaced)
    (effects (font (size 1.27 1.27)) (justify right))
    (property "Intersheetrefs" "${INTERSHEET_REFS}" (at 17.0602 73.5806 0)
      (effects (font (size 1.27 1.27)) (justify right) hide)
    )
  )
  (global_label "USB_RP_N" (shape input) (at 73.66 160.02 180) (fields_autoplaced)
    (effects (font (size 1.27 1.27)) (justify right))
    (property "Intersheetrefs" "${INTERSHEET_REFS}" (at 61.6312 159.9406 0)
      (effects (font (size 1.27 1.27)) (justify right) hide)
    )
  )
  (global_label "RESET_N" (shape input) (at 170.18 134.62 0) (fields_autoplaced)
    (effects (font (size 1.27 1.27)) (justify left))
    (property "Intersheetrefs" "${INTERSHEET_REFS}" (at 180.6364 134.5406 0)
      (effects (font (size 1.27 1.27)) (justify left) hide)
    )
  )
  (global_label "AUX_N" (shape input) (at 58.42 157.48 180) (fields_autoplaced)
    (effects (font (size 1.27 1.27)) (justify right))
    (property "Intersheetrefs" "${INTERSHEET_REFS}" (at 50.0802 157.4006 0)
      (effects (font (size 1.27 1.27)) (justify right) hide)
    )
  )
  (global_label "HPD" (shape input) (at 40.64 99.06 180) (fields_autoplaced)
    (effects (font (size 1.27 1.27)) (justify right))
    (property "Intersheetrefs" "${INTERSHEET_REFS}" (at 34.3564 98.9806 0)
      (effects (font (size 1.27 1.27)) (justify right) hide)
    )
  )
  (global_label "USB_T_P" (shape input) (at 142.24 86.36 0) (fields_autoplaced)
    (effects (font (size 1.27 1.27)) (justify left))
    (property "Intersheetrefs" "${INTERSHEET_REFS}" (at 152.636 86.2806 0)
      (effects (font (size 1.27 1.27)) (justify left) hide)
    )
  )
  (global_label "I2C1_SDA" (shape input) (at 27.94 68.58 180) (fields_autoplaced)
    (effects (font (size 1.27 1.27)) (justify right))
    (property "Intersheetrefs" "${INTERSHEET_REFS}" (at 16.6974 68.5006 0)
      (effects (font (size 1.27 1.27)) (justify right) hide)
    )
  )
  (global_label "3V3_SYS" (shape output) (at 384.81 48.26 0) (fields_autoplaced)
    (effects (font (size 1.27 1.27)) (justify left))
    (property "Intersheetrefs" "${INTERSHEET_REFS}" (at 395.206 48.1806 0)
      (effects (font (size 1.27 1.27)) (justify left) hide)
    )
  )
  (global_label "USB_T_N" (shape input) (at 142.24 88.9 0) (fields_autoplaced)
    (effects (font (size 1.27 1.27)) (justify left))
    (property "Intersheetrefs" "${INTERSHEET_REFS}" (at 152.6964 88.8206 0)
      (effects (font (size 1.27 1.27)) (justify left) hide)
    )
  )
  (global_label "5V0_USB" (shape input) (at 189.23 43.18 0) (fields_autoplaced)
    (effects (font (size 1.27 1.27)) (justify left))
    (property "Intersheetrefs" "${INTERSHEET_REFS}" (at 199.9283 43.2594 0)
      (effects (font (size 1.27 1.27)) (justify left) hide)
    )
  )
  (global_label "5V0_USB" (shape input) (at 31.75 207.01 180) (fields_autoplaced)
    (effects (font (size 1.27 1.27)) (justify right))
    (property "Intersheetrefs" "${INTERSHEET_REFS}" (at 21.0517 206.9306 0)
      (effects (font (size 1.27 1.27)) (justify right) hide)
    )
  )
  (global_label "SBU1" (shape input) (at 142.24 101.6 0) (fields_autoplaced)
    (effects (font (size 1.27 1.27)) (justify left))
    (property "Intersheetrefs" "${INTERSHEET_REFS}" (at 149.6726 101.5206 0)
      (effects (font (size 1.27 1.27)) (justify left) hide)
    )
  )
  (global_label "5V0_USB" (shape input) (at 214.63 43.18 180) (fields_autoplaced)
    (effects (font (size 1.27 1.27)) (justify right))
    (property "Intersheetrefs" "${INTERSHEET_REFS}" (at 203.9317 43.1006 0)
      (effects (font (size 1.27 1.27)) (justify right) hide)
    )
  )
  (global_label "I2C1_SCL" (shape input) (at 27.94 71.12 180) (fields_autoplaced)
    (effects (font (size 1.27 1.27)) (justify right))
    (property "Intersheetrefs" "${INTERSHEET_REFS}" (at 16.7579 71.0406 0)
      (effects (font (size 1.27 1.27)) (justify right) hide)
    )
  )
  (global_label "AUX_P" (shape input) (at 58.42 144.78 180) (fields_autoplaced)
    (effects (font (size 1.27 1.27)) (justify right))
    (property "Intersheetrefs" "${INTERSHEET_REFS}" (at 50.1407 144.7006 0)
      (effects (font (size 1.27 1.27)) (justify right) hide)
    )
  )
  (global_label "12V0_PCIE" (shape input) (at 387.35 146.05 0) (fields_autoplaced)
    (effects (font (size 1.27 1.27)) (justify left))
    (property "Intersheetrefs" "${INTERSHEET_REFS}" (at 399.7417 146.1294 0)
      (effects (font (size 1.27 1.27)) (justify left) hide)
    )
  )
  (global_label "CC2" (shape input) (at 189.23 73.66 0) (fields_autoplaced)
    (effects (font (size 1.27 1.27)) (justify left))
    (property "Intersheetrefs" "${INTERSHEET_REFS}" (at 195.3926 73.5806 0)
      (effects (font (size 1.27 1.27)) (justify left) hide)
    )
  )
  (global_label "USB_B_N" (shape input) (at 142.24 96.52 0) (fields_autoplaced)
    (effects (font (size 1.27 1.27)) (justify left))
    (property "Intersheetrefs" "${INTERSHEET_REFS}" (at 152.9988 96.5994 0)
      (effects (font (size 1.27 1.27)) (justify left) hide)
    )
  )
  (global_label "USB_RP_P" (shape input) (at 73.66 157.48 180) (fields_autoplaced)
    (effects (font (size 1.27 1.27)) (justify right))
    (property "Intersheetrefs" "${INTERSHEET_REFS}" (at 61.6917 157.4006 0)
      (effects (font (size 1.27 1.27)) (justify right) hide)
    )
  )
  (global_label "12V0_PCIE" (shape input) (at 299.72 146.05 0) (fields_autoplaced)
    (effects (font (size 1.27 1.27)) (justify left))
    (property "Intersheetrefs" "${INTERSHEET_REFS}" (at 312.1117 146.1294 0)
      (effects (font (size 1.27 1.27)) (justify left) hide)
    )
  )
  (global_label "3V3_SYS" (shape input) (at 39.37 54.61 180) (fields_autoplaced)
    (effects (font (size 1.27 1.27)) (justify right))
    (property "Intersheetrefs" "${INTERSHEET_REFS}" (at 28.974 54.6894 0)
      (effects (font (size 1.27 1.27)) (justify right) hide)
    )
  )
  (global_label "12V0_MOLEX" (shape input) (at 48.26 242.57 180) (fields_autoplaced)
    (effects (font (size 1.27 1.27)) (justify right))
    (property "Intersheetrefs" "${INTERSHEET_REFS}" (at 33.9936 242.6494 0)
      (effects (font (size 1.27 1.27)) (justify right) hide)
    )
  )
  (global_label "12V0_DCDC" (shape input) (at 278.13 212.09 0) (fields_autoplaced)
    (effects (font (size 1.27 1.27)) (justify left))
    (property "Intersheetrefs" "${INTERSHEET_REFS}" (at 291.3079 212.0106 0)
      (effects (font (size 1.27 1.27)) (justify left) hide)
    )
  )
  (global_label "SPI_MOSI" (shape input) (at 63.5 116.84 180) (fields_autoplaced)
    (effects (font (size 1.27 1.27)) (justify right))
    (property "Intersheetrefs" "${INTERSHEET_REFS}" (at 52.4388 116.7606 0)
      (effects (font (size 1.27 1.27)) (justify right) hide)
    )
  )
  (global_label "LSX_P2R" (shape input) (at 73.66 144.78 180) (fields_autoplaced)
    (effects (font (size 1.27 1.27)) (justify right))
    (property "Intersheetrefs" "${INTERSHEET_REFS}" (at 63.0826 144.7006 0)
      (effects (font (size 1.27 1.27)) (justify right) hide)
    )
  )
  (global_label "USB_B_P" (shape input) (at 142.24 93.98 0) (fields_autoplaced)
    (effects (font (size 1.27 1.27)) (justify left))
    (property "Intersheetrefs" "${INTERSHEET_REFS}" (at 152.9383 94.0594 0)
      (effects (font (size 1.27 1.27)) (justify left) hide)
    )
  )
  (global_label "SBU2" (shape input) (at 142.24 104.14 0) (fields_autoplaced)
    (effects (font (size 1.27 1.27)) (justify left))
    (property "Intersheetrefs" "${INTERSHEET_REFS}" (at 149.6726 104.0606 0)
      (effects (font (size 1.27 1.27)) (justify left) hide)
    )
  )

  (symbol (lib_id "antmicropower:GND") (at 193.04 220.98 0) (unit 1)
    (in_bom yes) (on_board yes) (dnp no)
    (property "Reference" "#PWR0179" (at 193.04 227.33 0)
      (effects (font (size 1.27 1.27)) hide)
    )
    (property "Value" "GND" (at 191.135 225.425 0)
      (effects (font (size 1.27 1.27) (thickness 0.15)) (justify left bottom))
    )
    (property "Footprint" "" (at 193.04 220.98 0)
      (effects (font (size 1.27 1.27) (thickness 0.15)) (justify left bottom) hide)
    )
    (property "Datasheet" "" (at 193.04 220.98 0)
      (effects (font (size 1.27 1.27) (thickness 0.15)) (justify left bottom) hide)
    )
    (property "Author" "Antmicro" (at 201.93 228.6 0)
      (effects (font (size 1.27 1.27) (thickness 0.15)) (justify left bottom) hide)
    )
    (property "License" "Apache-2.0" (at 201.93 231.14 0)
      (effects (font (size 1.27 1.27) (thickness 0.15)) (justify left bottom) hide)
    )
    (pin "1")
    (instances
      (project "thunderbolt-pcie-adapter"
        (path ""
          (reference "#PWR0179") (unit 1)
        )
      )
    )
  )

  (symbol (lib_id "antmicroTestPoints:TP_0.75mm_SMD") (at 134.62 240.03 0) (mirror y) (unit 1)
    (in_bom no) (on_board yes) (dnp no)
    (property "Reference" "TP6" (at 130.81 240.03 0)
      (effects (font (size 1.27 1.27) (thickness 0.15)) (justify left))
    )
    (property "Value" "TP_0.75mm_SMD" (at 129.54 240.0299 0)
      (effects (font (size 1.27 1.27) (thickness 0.15)) (justify left bottom) hide)
    )
    (property "Footprint" "antmicro-footprints:TP_SMD_0.75mm" (at 119.38 250.19 0)
      (effects (font (size 1.27 1.27) (thickness 0.15)) (justify left bottom) hide)
    )
    (property "Datasheet" "" (at 119.38 252.73 0)
      (effects (font (size 1.27 1.27) (thickness 0.15)) (justify left bottom) hide)
    )
    (property "License" "Apache-2.0" (at 119.38 257.81 0)
      (effects (font (size 1.27 1.27) (thickness 0.15)) (justify left bottom) hide)
    )
    (property "Manufacturer" "" (at 129.54 242.5699 0)
      (effects (font (size 1.27 1.27) (thickness 0.15)) (justify left bottom) hide)
    )
    (property "MPN" "" (at 134.62 240.03 0)
      (effects (font (size 1.27 1.27) (thickness 0.15)) (justify left bottom) hide)
    )
    (property "Author" "Antmicro" (at 119.38 255.27 0)
      (effects (font (size 1.27 1.27) (thickness 0.15)) (justify left bottom) hide)
    )
    (pin "1")
    (instances
      (project "thunderbolt-pcie-adapter"
        (path ""
          (reference "TP6") (unit 1)
        )
      )
    )
  )

  (symbol (lib_id "antmicropower:GND") (at 201.93 220.98 0) (unit 1)
    (in_bom yes) (on_board yes) (dnp no)
    (property "Reference" "#PWR0180" (at 201.93 227.33 0)
      (effects (font (size 1.27 1.27)) hide)
    )
    (property "Value" "GND" (at 200.025 225.425 0)
      (effects (font (size 1.27 1.27) (thickness 0.15)) (justify left bottom))
    )
    (property "Footprint" "" (at 201.93 220.98 0)
      (effects (font (size 1.27 1.27) (thickness 0.15)) (justify left bottom) hide)
    )
    (property "Datasheet" "" (at 201.93 220.98 0)
      (effects (font (size 1.27 1.27) (thickness 0.15)) (justify left bottom) hide)
    )
    (property "Author" "Antmicro" (at 210.82 228.6 0)
      (effects (font (size 1.27 1.27) (thickness 0.15)) (justify left bottom) hide)
    )
    (property "License" "Apache-2.0" (at 210.82 231.14 0)
      (effects (font (size 1.27 1.27) (thickness 0.15)) (justify left bottom) hide)
    )
    (pin "1")
    (instances
      (project "thunderbolt-pcie-adapter"
        (path ""
          (reference "#PWR0180") (unit 1)
        )
      )
    )
  )

  (symbol (lib_id "antmicroResistors0402:R_100k_0402") (at 130.81 266.7 90) (unit 1)
    (in_bom yes) (on_board yes) (dnp yes)
    (property "Reference" "R24" (at 128.27 262.89 90)
      (effects (font (size 1.27 1.27) (thickness 0.15)) (justify left))
    )
    (property "Value" "R_100k_0402" (at 143.51 246.38 0)
      (effects (font (size 1.27 1.27) (thickness 0.15)) (justify left bottom) hide)
    )
    (property "Footprint" "antmicro-footprints:R_0402_1005Metric" (at 146.05 246.38 0)
      (effects (font (size 1.27 1.27) (thickness 0.15)) (justify left bottom) hide)
    )
    (property "Datasheet" "https://www.bourns.com/docs/product-datasheets/cr.pdf" (at 148.59 246.38 0)
      (effects (font (size 1.27 1.27) (thickness 0.15)) (justify left bottom) hide)
    )
    (property "MPN" "CR0402-FX-1003GLF" (at 151.13 246.38 0)
      (effects (font (size 1.27 1.27) (thickness 0.15)) (justify left bottom) hide)
    )
    (property "Manufacturer" "Bourns" (at 153.67 246.38 0)
      (effects (font (size 1.27 1.27) (thickness 0.15)) (justify left bottom) hide)
    )
    (property "License" "Apache-2.0" (at 156.21 246.38 0)
      (effects (font (size 1.27 1.27) (thickness 0.15)) (justify left bottom) hide)
    )
    (property "Val" "100k" (at 128.27 265.43 90)
      (effects (font (size 1.27 1.27) (thickness 0.15)) (justify left))
    )
    (property "Tolerance" "1%" (at 140.97 246.38 0)
      (effects (font (size 1.27 1.27)) (justify left bottom) hide)
    )
    (property "Author" "Antmicro" (at 158.75 246.38 0)
      (effects (font (size 1.27 1.27) (thickness 0.15)) (justify left bottom) hide)
    )
    (pin "1")
    (pin "2")
    (instances
      (project "thunderbolt-pcie-adapter"
        (path ""
          (reference "R24") (unit 1)
        )
      )
    )
  )

  (symbol (lib_id "antmicroResistors0402:R_124k_0402") (at 175.26 259.08 270) (mirror x) (unit 1)
    (in_bom yes) (on_board yes) (dnp no)
    (property "Reference" "R28" (at 172.72 255.27 90)
      (effects (font (size 1.27 1.27) (thickness 0.15)) (justify right))
    )
    (property "Value" "R_124k_0402" (at 162.56 238.76 0)
      (effects (font (size 1.27 1.27) (thickness 0.15)) (justify left bottom) hide)
    )
    (property "Footprint" "antmicro-footprints:R_0402_1005Metric" (at 160.02 238.76 0)
      (effects (font (size 1.27 1.27) (thickness 0.15)) (justify left bottom) hide)
    )
    (property "Datasheet" "https://www.bourns.com/docs/product-datasheets/cr.pdf" (at 157.48 238.76 0)
      (effects (font (size 1.27 1.27) (thickness 0.15)) (justify left bottom) hide)
    )
    (property "MPN" "CR0402-FX-1243GLF" (at 154.94 238.76 0)
      (effects (font (size 1.27 1.27) (thickness 0.15)) (justify left bottom) hide)
    )
    (property "Manufacturer" "Bourns" (at 152.4 238.76 0)
      (effects (font (size 1.27 1.27) (thickness 0.15)) (justify left bottom) hide)
    )
    (property "License" "Apache-2.0" (at 149.86 238.76 0)
      (effects (font (size 1.27 1.27) (thickness 0.15)) (justify left bottom) hide)
    )
    (property "Author" "Antmicro" (at 147.32 238.76 0)
      (effects (font (size 1.27 1.27) (thickness 0.15)) (justify left bottom) hide)
    )
    (property "Val" "124k" (at 172.72 257.81 90)
      (effects (font (size 1.27 1.27) (thickness 0.15)) (justify right))
    )
    (property "Tolerance" "1%" (at 165.1 238.76 0)
      (effects (font (size 1.27 1.27)) (justify left bottom) hide)
    )
    (pin "1")
    (pin "2")
    (instances
      (project "thunderbolt-pcie-adapter"
        (path ""
          (reference "R28") (unit 1)
        )
      )
    )
  )

  (symbol (lib_id "antmicropower:GND") (at 175.26 266.7 0) (unit 1)
    (in_bom yes) (on_board yes) (dnp no)
    (property "Reference" "#PWR0176" (at 175.26 273.05 0)
      (effects (font (size 1.27 1.27)) hide)
    )
    (property "Value" "GND" (at 173.355 271.145 0)
      (effects (font (size 1.27 1.27) (thickness 0.15)) (justify left bottom))
    )
    (property "Footprint" "" (at 175.26 266.7 0)
      (effects (font (size 1.27 1.27) (thickness 0.15)) (justify left bottom) hide)
    )
    (property "Datasheet" "" (at 175.26 266.7 0)
      (effects (font (size 1.27 1.27) (thickness 0.15)) (justify left bottom) hide)
    )
    (property "Author" "Antmicro" (at 184.15 274.32 0)
      (effects (font (size 1.27 1.27) (thickness 0.15)) (justify left bottom) hide)
    )
    (property "License" "Apache-2.0" (at 184.15 276.86 0)
      (effects (font (size 1.27 1.27) (thickness 0.15)) (justify left bottom) hide)
    )
    (pin "1")
    (instances
      (project "thunderbolt-pcie-adapter"
        (path ""
          (reference "#PWR0176") (unit 1)
        )
      )
    )
  )

  (symbol (lib_id "antmicropower:GND") (at 271.78 53.34 0) (unit 1)
    (in_bom yes) (on_board yes) (dnp no)
    (property "Reference" "#PWR027" (at 271.78 59.69 0)
      (effects (font (size 1.27 1.27)) hide)
    )
    (property "Value" "GND" (at 269.875 57.785 0)
      (effects (font (size 1.27 1.27) (thickness 0.15)) (justify left bottom))
    )
    (property "Footprint" "" (at 271.78 53.34 0)
      (effects (font (size 1.27 1.27) (thickness 0.15)) (justify left bottom) hide)
    )
    (property "Datasheet" "" (at 271.78 53.34 0)
      (effects (font (size 1.27 1.27) (thickness 0.15)) (justify left bottom) hide)
    )
    (property "Author" "Antmicro" (at 280.67 60.96 0)
      (effects (font (size 1.27 1.27) (thickness 0.15)) (justify left bottom) hide)
    )
    (property "License" "Apache-2.0" (at 280.67 63.5 0)
      (effects (font (size 1.27 1.27) (thickness 0.15)) (justify left bottom) hide)
    )
    (pin "1")
    (instances
      (project "thunderbolt-pcie-adapter"
        (path ""
          (reference "#PWR027") (unit 1)
        )
      )
    )
  )

  (symbol (lib_id "antmicropower:GND") (at 210.82 220.98 0) (unit 1)
    (in_bom yes) (on_board yes) (dnp no)
    (property "Reference" "#PWR0181" (at 210.82 227.33 0)
      (effects (font (size 1.27 1.27)) hide)
    )
    (property "Value" "GND" (at 208.915 225.425 0)
      (effects (font (size 1.27 1.27) (thickness 0.15)) (justify left bottom))
    )
    (property "Footprint" "" (at 210.82 220.98 0)
      (effects (font (size 1.27 1.27) (thickness 0.15)) (justify left bottom) hide)
    )
    (property "Datasheet" "" (at 210.82 220.98 0)
      (effects (font (size 1.27 1.27) (thickness 0.15)) (justify left bottom) hide)
    )
    (property "Author" "Antmicro" (at 219.71 228.6 0)
      (effects (font (size 1.27 1.27) (thickness 0.15)) (justify left bottom) hide)
    )
    (property "License" "Apache-2.0" (at 219.71 231.14 0)
      (effects (font (size 1.27 1.27) (thickness 0.15)) (justify left bottom) hide)
    )
    (pin "1")
    (instances
      (project "thunderbolt-pcie-adapter"
        (path ""
          (reference "#PWR0181") (unit 1)
        )
      )
    )
  )

  (symbol (lib_id "antmicroDCDCConverters:MP2386GG") (at 289.56 57.15 0) (unit 1)
    (in_bom yes) (on_board yes) (dnp no)
    (property "Reference" "U2" (at 297.815 50.8 0)
      (effects (font (size 1.27 1.27) (thickness 0.15)))
    )
    (property "Value" "MP2386GG" (at 322.58 64.77 0)
      (effects (font (size 1.27 1.27) (thickness 0.15)) (justify left bottom) hide)
    )
    (property "Footprint" "antmicro-footprints:QFN-11_2x2mm_P0.5mm" (at 322.58 67.31 0)
      (effects (font (size 1.27 1.27) (thickness 0.15)) (justify left bottom) hide)
    )
    (property "Datasheet" "https://www.monolithicpower.com/en/documentview/productdocument/index/version/2/document_type/Datasheet/lang/en/sku/MP2386GG-Z/document_id/4066/" (at 322.58 69.85 0)
      (effects (font (size 1.27 1.27) (thickness 0.15)) (justify left bottom) hide)
    )
    (property "Manufacturer" "Monolithic Power Systems" (at 322.58 72.39 0)
      (effects (font (size 1.27 1.27) (thickness 0.15)) (justify left bottom) hide)
    )
    (property "MPN" "MP2386GG-P" (at 292.1 53.975 0)
      (effects (font (size 1.27 1.27) (thickness 0.15)) (justify left bottom))
    )
    (property "License" "Apache-2.0" (at 322.58 80.01 0)
      (effects (font (size 1.27 1.27) (thickness 0.15)) (justify left bottom) hide)
    )
    (property "Author" "Antmicro" (at 322.58 77.47 0)
      (effects (font (size 1.27 1.27) (thickness 0.15)) (justify left bottom) hide)
    )
    (pin "1")
    (pin "10")
    (pin "11")
    (pin "2")
    (pin "3")
    (pin "4")
    (pin "5")
    (pin "6")
    (pin "7")
    (pin "8")
    (pin "9")
    (instances
      (project "thunderbolt-pcie-adapter"
        (path ""
          (reference "U2") (unit 1)
        )
      )
    )
  )

  (symbol (lib_id "antmicroFerriteBeadsandChips:FB_30Z_8.5A_Murata-BLM21SN_0805") (at 375.92 57.15 270) (mirror x) (unit 1)
    (in_bom yes) (on_board yes) (dnp no) (fields_autoplaced)
    (property "Reference" "FB3" (at 379.095 53.3781 90)
      (effects (font (size 1.27 1.27) (thickness 0.15)) (justify left))
    )
    (property "Value" "FB_30Z_8.5A_Murata-BLM21SN_0805" (at 373.38 43.18 0)
      (effects (font (size 1.27 1.27) (thickness 0.15)) (justify left bottom) hide)
    )
    (property "Footprint" "antmicro-footprints:FB_0805_2012Metric" (at 368.3 43.18 0)
      (effects (font (size 1.27 1.27) (thickness 0.15)) (justify left bottom) hide)
    )
    (property "Datasheet" "https://www.murata.com/en-sg/products/productdata/8796738977822/ENFA0005.pdf?1519270210000" (at 365.76 43.18 0)
      (effects (font (size 1.27 1.27) (thickness 0.15)) (justify left bottom) hide)
    )
    (property "MPN" "BLM21SN300SZ1D" (at 363.22 43.18 0)
      (effects (font (size 1.27 1.27) (thickness 0.15)) (justify left bottom) hide)
    )
    (property "Manufacturer" "Murata" (at 360.68 43.18 0)
      (effects (font (size 1.27 1.27) (thickness 0.15)) (justify left bottom) hide)
    )
    (property "License" "Apache-2.0" (at 355.6 43.18 0)
      (effects (font (size 1.27 1.27) (thickness 0.15)) (justify left bottom) hide)
    )
    (property "Author" "Antmicro" (at 358.14 43.18 0)
      (effects (font (size 1.27 1.27) (thickness 0.15)) (justify left bottom) hide)
    )
    (property "Val" "30Z/8.5A" (at 379.095 55.9181 90)
      (effects (font (size 1.27 1.27)) (justify left))
    )
    (property "Current" "" (at 353.06 36.83 0)
      (effects (font (size 1.27 1.27) (thickness 0.15)) (justify left bottom) hide)
    )
    (pin "1")
    (pin "2")
    (instances
      (project "thunderbolt-pcie-adapter"
        (path ""
          (reference "FB3") (unit 1)
        )
      )
    )
  )

  (symbol (lib_id "antmicroInterfaceControllers:TPS65983BAZBHR") (at 74.93 38.1 0) (unit 1)
    (in_bom yes) (on_board yes) (dnp no) (fields_autoplaced)
    (property "Reference" "U3" (at 104.14 27.94 0)
      (effects (font (size 1.27 1.27) (thickness 0.15)))
    )
    (property "Value" "TPS65983BAZBHR" (at 148.59 38.1 0)
      (effects (font (size 1.27 1.27) (thickness 0.15)) (justify left bottom) hide)
    )
    (property "Footprint" "antmicro-footprints:IC_TPS65983BAZBHR" (at 148.59 40.64 0)
      (effects (font (size 1.27 1.27) (thickness 0.15)) (justify left bottom) hide)
    )
    (property "Datasheet" "https://www.ti.com/lit/ds/symlink/tps65983b.pdf?ts=1678712702533&ref_url=https%253A%252F%252Fwww.ti.com%252Fproduct%252FTPS65983B" (at 148.59 43.18 0)
      (effects (font (size 1.27 1.27) (thickness 0.15)) (justify left bottom) hide)
    )
    (property "MPN" "TPS65983BAZBHR" (at 104.14 30.48 0)
      (effects (font (size 1.27 1.27) (thickness 0.15)))
    )
    (property "Manufacturer" "Texas Instruments" (at 148.59 48.26 0)
      (effects (font (size 1.27 1.27) (thickness 0.15)) (justify left bottom) hide)
    )
    (property "License" "Apache-2.0" (at 148.59 53.34 0)
      (effects (font (size 1.27 1.27) (thickness 0.15)) (justify left bottom) hide)
    )
    (property "Author" "Antmicro" (at 148.59 50.8 0)
      (effects (font (size 1.27 1.27) (thickness 0.15)) (justify left bottom) hide)
    )
    (pin "A1")
    (pin "A10")
    (pin "A11")
    (pin "A2")
    (pin "A3")
    (pin "A4")
    (pin "A5")
    (pin "A6")
    (pin "A7")
    (pin "A8")
    (pin "A9")
    (pin "B1")
    (pin "B10")
    (pin "B11")
    (pin "B2")
    (pin "B3")
    (pin "B4")
    (pin "B5")
    (pin "B6")
    (pin "B7")
    (pin "B8")
    (pin "B9")
    (pin "C1")
    (pin "C10")
    (pin "C11")
    (pin "C2")
    (pin "D1")
    (pin "D10")
    (pin "D11")
    (pin "D2")
    (pin "D5")
    (pin "D6")
    (pin "D7")
    (pin "D8")
    (pin "E1")
    (pin "E10")
    (pin "E11")
    (pin "E2")
    (pin "E4")
    (pin "E5")
    (pin "E6")
    (pin "E7")
    (pin "E8")
    (pin "F1")
    (pin "F10")
    (pin "F11")
    (pin "F2")
    (pin "F4")
    (pin "F5")
    (pin "F6")
    (pin "F7")
    (pin "F8")
    (pin "G1")
    (pin "G10")
    (pin "G11")
    (pin "G2")
    (pin "G4")
    (pin "G5")
    (pin "G6")
    (pin "G7")
    (pin "G8")
    (pin "H1")
    (pin "H10")
    (pin "H11")
    (pin "H2")
    (pin "H4")
    (pin "H5")
    (pin "H6")
    (pin "H7")
    (pin "H8")
    (pin "J1")
    (pin "J10")
    (pin "J11")
    (pin "J2")
    (pin "K1")
    (pin "K10")
    (pin "K11")
    (pin "K2")
    (pin "K3")
    (pin "K4")
    (pin "K5")
    (pin "K6")
    (pin "K7")
    (pin "K8")
    (pin "K9")
    (pin "L1")
    (pin "L10")
    (pin "L11")
    (pin "L2")
    (pin "L3")
    (pin "L4")
    (pin "L5")
    (pin "L6")
    (pin "L7")
    (pin "L8")
    (pin "L9")
    (instances
      (project "thunderbolt-pcie-adapter"
        (path ""
          (reference "U3") (unit 1)
        )
      )
    )
  )

  (symbol (lib_id "antmicropower:GND") (at 262.89 76.2 0) (unit 1)
    (in_bom yes) (on_board yes) (dnp no) (fields_autoplaced)
    (property "Reference" "#PWR035" (at 262.89 82.55 0)
      (effects (font (size 1.27 1.27)) hide)
    )
    (property "Value" "GND" (at 260.985 80.645 0)
      (effects (font (size 1.27 1.27) (thickness 0.15)) (justify left bottom))
    )
    (property "Footprint" "" (at 262.89 76.2 0)
      (effects (font (size 1.27 1.27) (thickness 0.15)) (justify left bottom) hide)
    )
    (property "Datasheet" "" (at 262.89 76.2 0)
      (effects (font (size 1.27 1.27) (thickness 0.15)) (justify left bottom) hide)
    )
    (property "Author" "Antmicro" (at 271.78 83.82 0)
      (effects (font (size 1.27 1.27) (thickness 0.15)) (justify left bottom) hide)
    )
    (property "License" "Apache-2.0" (at 271.78 86.36 0)
      (effects (font (size 1.27 1.27) (thickness 0.15)) (justify left bottom) hide)
    )
    (pin "1")
    (instances
      (project "thunderbolt-pcie-adapter"
        (path ""
          (reference "#PWR035") (unit 1)
        )
      )
    )
  )

  (symbol (lib_id "antmicroCapacitors0402:C_220p_0402") (at 184.15 83.82 90) (unit 1)
    (in_bom yes) (on_board yes) (dnp no)
    (property "Reference" "C49" (at 186.055 80.01 90)
      (effects (font (size 1.27 1.27) (thickness 0.15)) (justify right))
    )
    (property "Value" "C_220p_0402" (at 194.31 63.5 0)
      (effects (font (size 1.27 1.27) (thickness 0.15)) (justify left bottom) hide)
    )
    (property "Footprint" "antmicro-footprints:C_0402_1005Metric" (at 196.85 63.5 0)
      (effects (font (size 1.27 1.27) (thickness 0.15)) (justify left bottom) hide)
    )
    (property "Datasheet" "https://spicat.kyocera-avx.com/product/mlcc/chartview/04025C221JAT2A/" (at 199.39 63.5 0)
      (effects (font (size 1.27 1.27) (thickness 0.15)) (justify left bottom) hide)
    )
    (property "MPN" "04025C221JAT2A" (at 201.93 63.5 0)
      (effects (font (size 1.27 1.27) (thickness 0.15)) (justify left bottom) hide)
    )
    (property "Manufacturer" "KYOCERA AVX" (at 204.47 63.5 0)
      (effects (font (size 1.27 1.27) (thickness 0.15)) (justify left bottom) hide)
    )
    (property "License" "Apache-2.0" (at 207.01 63.5 0)
      (effects (font (size 1.27 1.27) (thickness 0.15)) (justify left bottom) hide)
    )
    (property "Val" "220p" (at 191.135 81.28 90)
      (effects (font (size 1.27 1.27) (thickness 0.15)) (justify left bottom))
    )
    (property "Voltage" "" (at 212.09 63.5 0)
      (effects (font (size 1.27 1.27)) (justify left bottom) hide)
    )
    (property "Dielectric" "" (at 214.63 63.5 0)
      (effects (font (size 1.27 1.27)) (justify left bottom) hide)
    )
    (property "Author" "Antmicro" (at 209.55 63.5 0)
      (effects (font (size 1.27 1.27) (thickness 0.15)) (justify left bottom) hide)
    )
    (pin "1")
    (pin "2")
    (instances
      (project "thunderbolt-pcie-adapter"
        (path ""
          (reference "C49") (unit 1)
        )
      )
    )
  )

  (symbol (lib_id "antmicropower:GND") (at 228.6 220.98 0) (unit 1)
    (in_bom yes) (on_board yes) (dnp no)
    (property "Reference" "#PWR0183" (at 228.6 227.33 0)
      (effects (font (size 1.27 1.27)) hide)
    )
    (property "Value" "GND" (at 226.695 225.425 0)
      (effects (font (size 1.27 1.27) (thickness 0.15)) (justify left bottom))
    )
    (property "Footprint" "" (at 228.6 220.98 0)
      (effects (font (size 1.27 1.27) (thickness 0.15)) (justify left bottom) hide)
    )
    (property "Datasheet" "" (at 228.6 220.98 0)
      (effects (font (size 1.27 1.27) (thickness 0.15)) (justify left bottom) hide)
    )
    (property "Author" "Antmicro" (at 237.49 228.6 0)
      (effects (font (size 1.27 1.27) (thickness 0.15)) (justify left bottom) hide)
    )
    (property "License" "Apache-2.0" (at 237.49 231.14 0)
      (effects (font (size 1.27 1.27) (thickness 0.15)) (justify left bottom) hide)
    )
    (pin "1")
    (instances
      (project "thunderbolt-pcie-adapter"
        (path ""
          (reference "#PWR0183") (unit 1)
        )
      )
    )
  )

  (symbol (lib_id "antmicroResistors0402:R_10k_0402") (at 247.65 72.39 90) (unit 1)
    (in_bom yes) (on_board yes) (dnp no)
    (property "Reference" "R11" (at 248.92 68.58 90)
      (effects (font (size 1.27 1.27) (thickness 0.15)) (justify right))
    )
    (property "Value" "R_10k_0402" (at 260.35 52.07 0)
      (effects (font (size 1.27 1.27) (thickness 0.15)) (justify left bottom) hide)
    )
    (property "Footprint" "antmicro-footprints:R_0402_1005Metric" (at 262.89 52.07 0)
      (effects (font (size 1.27 1.27) (thickness 0.15)) (justify left bottom) hide)
    )
    (property "Datasheet" "https://www.bourns.com/docs/product-datasheets/cr.pdf" (at 265.43 52.07 0)
      (effects (font (size 1.27 1.27) (thickness 0.15)) (justify left bottom) hide)
    )
    (property "MPN" "CR0402-FX-1002GLF" (at 267.97 52.07 0)
      (effects (font (size 1.27 1.27) (thickness 0.15)) (justify left bottom) hide)
    )
    (property "Manufacturer" "Bourns" (at 270.51 52.07 0)
      (effects (font (size 1.27 1.27) (thickness 0.15)) (justify left bottom) hide)
    )
    (property "License" "Apache-2.0" (at 273.05 52.07 0)
      (effects (font (size 1.27 1.27) (thickness 0.15)) (justify left bottom) hide)
    )
    (property "Val" "10k" (at 252.73 69.85 90)
      (effects (font (size 1.27 1.27) (thickness 0.15)) (justify left bottom))
    )
    (property "Tolerance" "1%" (at 257.81 52.07 0)
      (effects (font (size 1.27 1.27)) (justify left bottom) hide)
    )
    (property "Author" "Antmicro" (at 275.59 52.07 0)
      (effects (font (size 1.27 1.27) (thickness 0.15)) (justify left bottom) hide)
    )
    (pin "1")
    (pin "2")
    (instances
      (project "thunderbolt-pcie-adapter"
        (path ""
          (reference "R11") (unit 1)
        )
      )
    )
  )

  (symbol (lib_id "antmicropower:GND") (at 175.26 54.61 0) (unit 1)
    (in_bom yes) (on_board yes) (dnp no)
    (property "Reference" "#PWR0159" (at 175.26 60.96 0)
      (effects (font (size 1.27 1.27)) hide)
    )
    (property "Value" "GND" (at 173.355 59.055 0)
      (effects (font (size 1.27 1.27) (thickness 0.15)) (justify left bottom))
    )
    (property "Footprint" "" (at 175.26 54.61 0)
      (effects (font (size 1.27 1.27) (thickness 0.15)) (justify left bottom) hide)
    )
    (property "Datasheet" "" (at 175.26 54.61 0)
      (effects (font (size 1.27 1.27) (thickness 0.15)) (justify left bottom) hide)
    )
    (property "Author" "Antmicro" (at 184.15 62.23 0)
      (effects (font (size 1.27 1.27) (thickness 0.15)) (justify left bottom) hide)
    )
    (property "License" "Apache-2.0" (at 184.15 64.77 0)
      (effects (font (size 1.27 1.27) (thickness 0.15)) (justify left bottom) hide)
    )
    (pin "1")
    (instances
      (project "thunderbolt-pcie-adapter"
        (path ""
          (reference "#PWR0159") (unit 1)
        )
      )
    )
  )

  (symbol (lib_id "antmicroResistors0402:R_110k_0402") (at 241.3 226.06 90) (unit 1)
    (in_bom yes) (on_board yes) (dnp no) (fields_autoplaced)
    (property "Reference" "R43" (at 238.76 222.25 90)
      (effects (font (size 1.27 1.27) (thickness 0.15)) (justify left))
    )
    (property "Value" "R_110k_0402" (at 254 205.74 0)
      (effects (font (size 1.27 1.27) (thickness 0.15)) (justify left bottom) hide)
    )
    (property "Footprint" "antmicro-footprints:R_0402_1005Metric" (at 256.54 205.74 0)
      (effects (font (size 1.27 1.27) (thickness 0.15)) (justify left bottom) hide)
    )
    (property "Datasheet" "https://www.bourns.com/docs/product-datasheets/cr.pdf" (at 259.08 205.74 0)
      (effects (font (size 1.27 1.27) (thickness 0.15)) (justify left bottom) hide)
    )
    (property "MPN" "CR0402-FX-1103GLF" (at 261.62 205.74 0)
      (effects (font (size 1.27 1.27) (thickness 0.15)) (justify left bottom) hide)
    )
    (property "Manufacturer" "Bourns" (at 264.16 205.74 0)
      (effects (font (size 1.27 1.27) (thickness 0.15)) (justify left bottom) hide)
    )
    (property "License" "Apache-2.0" (at 266.7 205.74 0)
      (effects (font (size 1.27 1.27) (thickness 0.15)) (justify left bottom) hide)
    )
    (property "Val" "110k" (at 238.76 224.79 90)
      (effects (font (size 1.27 1.27) (thickness 0.15)) (justify left))
    )
    (property "Tolerance" "1%" (at 251.46 205.74 0)
      (effects (font (size 1.27 1.27)) (justify left bottom) hide)
    )
    (property "Author" "Antmicro" (at 269.24 205.74 0)
      (effects (font (size 1.27 1.27) (thickness 0.15)) (justify left bottom) hide)
    )
    (pin "1")
    (pin "2")
    (instances
      (project "thunderbolt-pcie-adapter"
        (path ""
          (reference "R43") (unit 1)
        )
      )
    )
  )

  (symbol (lib_id "antmicroCapacitors0402:C_220n_0402") (at 134.62 167.64 90) (unit 1)
    (in_bom yes) (on_board yes) (dnp no)
    (property "Reference" "C31" (at 137.795 163.8235 90)
      (effects (font (size 1.27 1.27) (thickness 0.15)) (justify right))
    )
    (property "Value" "C_220n_0402" (at 144.78 147.32 0)
      (effects (font (size 1.27 1.27) (thickness 0.15)) (justify left bottom) hide)
    )
    (property "Footprint" "antmicro-footprints:C_0402_1005Metric" (at 147.32 147.32 0)
      (effects (font (size 1.27 1.27) (thickness 0.15)) (justify left bottom) hide)
    )
    (property "Datasheet" "https://www.yageo.com/en/Chart/Download/pdf/CC0402KRX5R6BB224" (at 149.86 147.32 0)
      (effects (font (size 1.27 1.27) (thickness 0.15)) (justify left bottom) hide)
    )
    (property "MPN" "CC0402KRX5R6BB224" (at 152.4 147.32 0)
      (effects (font (size 1.27 1.27) (thickness 0.15)) (justify left bottom) hide)
    )
    (property "Manufacturer" "YAGEO" (at 154.94 147.32 0)
      (effects (font (size 1.27 1.27) (thickness 0.15)) (justify left bottom) hide)
    )
    (property "License" "Apache-2.0" (at 157.48 147.32 0)
      (effects (font (size 1.27 1.27) (thickness 0.15)) (justify left bottom) hide)
    )
    (property "Val" "220n" (at 142.875 165.1 90)
      (effects (font (size 1.27 1.27) (thickness 0.15)) (justify left bottom))
    )
    (property "Voltage" "" (at 162.56 147.32 0)
      (effects (font (size 1.27 1.27)) (justify left bottom) hide)
    )
    (property "Dielectric" "" (at 165.1 147.32 0)
      (effects (font (size 1.27 1.27)) (justify left bottom) hide)
    )
    (property "Author" "Antmicro" (at 160.02 147.32 0)
      (effects (font (size 1.27 1.27) (thickness 0.15)) (justify left bottom) hide)
    )
    (pin "1")
    (pin "2")
    (instances
      (project "thunderbolt-pcie-adapter"
        (path ""
          (reference "C31") (unit 1)
        )
      )
    )
  )

  (symbol (lib_id "antmicropower:GND") (at 262.89 53.34 0) (unit 1)
    (in_bom yes) (on_board yes) (dnp no)
    (property "Reference" "#PWR023" (at 262.89 59.69 0)
      (effects (font (size 1.27 1.27)) hide)
    )
    (property "Value" "GND" (at 260.985 57.785 0)
      (effects (font (size 1.27 1.27) (thickness 0.15)) (justify left bottom))
    )
    (property "Footprint" "" (at 262.89 53.34 0)
      (effects (font (size 1.27 1.27) (thickness 0.15)) (justify left bottom) hide)
    )
    (property "Datasheet" "" (at 262.89 53.34 0)
      (effects (font (size 1.27 1.27) (thickness 0.15)) (justify left bottom) hide)
    )
    (property "Author" "Antmicro" (at 271.78 60.96 0)
      (effects (font (size 1.27 1.27) (thickness 0.15)) (justify left bottom) hide)
    )
    (property "License" "Apache-2.0" (at 271.78 63.5 0)
      (effects (font (size 1.27 1.27) (thickness 0.15)) (justify left bottom) hide)
    )
    (pin "1")
    (instances
      (project "thunderbolt-pcie-adapter"
        (path ""
          (reference "#PWR023") (unit 1)
        )
      )
    )
  )

  (symbol (lib_id "antmicropower:GND") (at 247.65 76.2 0) (unit 1)
    (in_bom yes) (on_board yes) (dnp no)
    (property "Reference" "#PWR026" (at 247.65 82.55 0)
      (effects (font (size 1.27 1.27)) hide)
    )
    (property "Value" "GND" (at 245.745 80.645 0)
      (effects (font (size 1.27 1.27) (thickness 0.15)) (justify left bottom))
    )
    (property "Footprint" "" (at 247.65 76.2 0)
      (effects (font (size 1.27 1.27) (thickness 0.15)) (justify left bottom) hide)
    )
    (property "Datasheet" "" (at 247.65 76.2 0)
      (effects (font (size 1.27 1.27) (thickness 0.15)) (justify left bottom) hide)
    )
    (property "Author" "Antmicro" (at 256.54 83.82 0)
      (effects (font (size 1.27 1.27) (thickness 0.15)) (justify left bottom) hide)
    )
    (property "License" "Apache-2.0" (at 256.54 86.36 0)
      (effects (font (size 1.27 1.27) (thickness 0.15)) (justify left bottom) hide)
    )
    (pin "1")
    (instances
      (project "thunderbolt-pcie-adapter"
        (path ""
          (reference "#PWR026") (unit 1)
        )
      )
    )
  )

  (symbol (lib_id "antmicropower:GND") (at 281.94 53.34 0) (unit 1)
    (in_bom yes) (on_board yes) (dnp no)
    (property "Reference" "#PWR036" (at 281.94 59.69 0)
      (effects (font (size 1.27 1.27)) hide)
    )
    (property "Value" "GND" (at 280.035 57.785 0)
      (effects (font (size 1.27 1.27) (thickness 0.15)) (justify left bottom))
    )
    (property "Footprint" "" (at 281.94 53.34 0)
      (effects (font (size 1.27 1.27) (thickness 0.15)) (justify left bottom) hide)
    )
    (property "Datasheet" "" (at 281.94 53.34 0)
      (effects (font (size 1.27 1.27) (thickness 0.15)) (justify left bottom) hide)
    )
    (property "Author" "Antmicro" (at 290.83 60.96 0)
      (effects (font (size 1.27 1.27) (thickness 0.15)) (justify left bottom) hide)
    )
    (property "License" "Apache-2.0" (at 290.83 63.5 0)
      (effects (font (size 1.27 1.27) (thickness 0.15)) (justify left bottom) hide)
    )
    (pin "1")
    (instances
      (project "thunderbolt-pcie-adapter"
        (path ""
          (reference "#PWR036") (unit 1)
        )
      )
    )
  )

  (symbol (lib_id "antmicroCapacitors0402:C_100n_0402") (at 170.18 245.11 0) (mirror x) (unit 1)
    (in_bom yes) (on_board yes) (dnp no)
    (property "Reference" "C28" (at 177.165 247.015 0)
      (effects (font (size 1.27 1.27) (thickness 0.15)) (justify right))
    )
    (property "Value" "C_100n_0402" (at 190.5 234.95 0)
      (effects (font (size 1.27 1.27) (thickness 0.15)) (justify left bottom) hide)
    )
    (property "Footprint" "antmicro-footprints:C_0402_1005Metric" (at 190.5 232.41 0)
      (effects (font (size 1.27 1.27) (thickness 0.15)) (justify left bottom) hide)
    )
    (property "Datasheet" "https://www.murata.com/products/productdetail?partno=GRM155R61H104KE14%23" (at 190.5 229.87 0)
      (effects (font (size 1.27 1.27) (thickness 0.15)) (justify left bottom) hide)
    )
    (property "MPN" "GRM155R61H104KE14D" (at 190.5 227.33 0)
      (effects (font (size 1.27 1.27) (thickness 0.15)) (justify left bottom) hide)
    )
    (property "Manufacturer" "Murata" (at 190.5 224.79 0)
      (effects (font (size 1.27 1.27) (thickness 0.15)) (justify left bottom) hide)
    )
    (property "License" "Apache-2.0" (at 190.5 222.25 0)
      (effects (font (size 1.27 1.27) (thickness 0.15)) (justify left bottom) hide)
    )
    (property "Val" "100n" (at 167.005 246.38 0)
      (effects (font (size 1.27 1.27) (thickness 0.15)) (justify left bottom))
    )
    (property "Voltage" "50V" (at 190.5 217.17 0)
      (effects (font (size 1.27 1.27)) (justify left bottom) hide)
    )
    (property "Dielectric" "X5R" (at 190.5 214.63 0)
      (effects (font (size 1.27 1.27)) (justify left bottom) hide)
    )
    (property "Author" "Antmicro" (at 190.5 219.71 0)
      (effects (font (size 1.27 1.27) (thickness 0.15)) (justify left bottom) hide)
    )
    (pin "1")
    (pin "2")
    (instances
      (project "thunderbolt-pcie-adapter"
        (path ""
          (reference "C28") (unit 1)
        )
      )
    )
  )

  (symbol (lib_id "antmicroCapacitors0402:C_100n_0402") (at 193.04 219.71 270) (mirror x) (unit 1)
    (in_bom yes) (on_board yes) (dnp no) (fields_autoplaced)
    (property "Reference" "C32" (at 195.58 215.8936 90)
      (effects (font (size 1.27 1.27) (thickness 0.15)) (justify left))
    )
    (property "Value" "C_100n_0402" (at 182.88 199.39 0)
      (effects (font (size 1.27 1.27) (thickness 0.15)) (justify left bottom) hide)
    )
    (property "Footprint" "antmicro-footprints:C_0402_1005Metric" (at 180.34 199.39 0)
      (effects (font (size 1.27 1.27) (thickness 0.15)) (justify left bottom) hide)
    )
    (property "Datasheet" "https://www.murata.com/products/productdetail?partno=GRM155R61H104KE14%23" (at 177.8 199.39 0)
      (effects (font (size 1.27 1.27) (thickness 0.15)) (justify left bottom) hide)
    )
    (property "MPN" "GRM155R61H104KE14D" (at 175.26 199.39 0)
      (effects (font (size 1.27 1.27) (thickness 0.15)) (justify left bottom) hide)
    )
    (property "Manufacturer" "Murata" (at 172.72 199.39 0)
      (effects (font (size 1.27 1.27) (thickness 0.15)) (justify left bottom) hide)
    )
    (property "License" "Apache-2.0" (at 170.18 199.39 0)
      (effects (font (size 1.27 1.27) (thickness 0.15)) (justify left bottom) hide)
    )
    (property "Val" "100n" (at 195.58 218.4336 90)
      (effects (font (size 1.27 1.27) (thickness 0.15)) (justify left))
    )
    (property "Voltage" "50V" (at 165.1 199.39 0)
      (effects (font (size 1.27 1.27)) (justify left bottom) hide)
    )
    (property "Dielectric" "X5R" (at 162.56 199.39 0)
      (effects (font (size 1.27 1.27)) (justify left bottom) hide)
    )
    (property "Author" "Antmicro" (at 167.64 199.39 0)
      (effects (font (size 1.27 1.27) (thickness 0.15)) (justify left bottom) hide)
    )
    (pin "1")
    (pin "2")
    (instances
      (project "thunderbolt-pcie-adapter"
        (path ""
          (reference "C32") (unit 1)
        )
      )
    )
  )

  (symbol (lib_id "antmicroResistors0402:R_10k_0402") (at 247.65 45.72 270) (unit 1)
    (in_bom yes) (on_board yes) (dnp no) (fields_autoplaced)
    (property "Reference" "R6" (at 245.745 46.99 90)
      (effects (font (size 1.27 1.27) (thickness 0.15)) (justify right))
    )
    (property "Value" "R_10k_0402" (at 234.95 66.04 0)
      (effects (font (size 1.27 1.27) (thickness 0.15)) (justify left bottom) hide)
    )
    (property "Footprint" "antmicro-footprints:R_0402_1005Metric" (at 232.41 66.04 0)
      (effects (font (size 1.27 1.27) (thickness 0.15)) (justify left bottom) hide)
    )
    (property "Datasheet" "https://www.bourns.com/docs/product-datasheets/cr.pdf" (at 229.87 66.04 0)
      (effects (font (size 1.27 1.27) (thickness 0.15)) (justify left bottom) hide)
    )
    (property "MPN" "CR0402-FX-1002GLF" (at 227.33 66.04 0)
      (effects (font (size 1.27 1.27) (thickness 0.15)) (justify left bottom) hide)
    )
    (property "Manufacturer" "Bourns" (at 224.79 66.04 0)
      (effects (font (size 1.27 1.27) (thickness 0.15)) (justify left bottom) hide)
    )
    (property "License" "Apache-2.0" (at 222.25 66.04 0)
      (effects (font (size 1.27 1.27) (thickness 0.15)) (justify left bottom) hide)
    )
    (property "Val" "10k" (at 245.745 49.53 90)
      (effects (font (size 1.27 1.27) (thickness 0.15)) (justify right))
    )
    (property "Tolerance" "1%" (at 237.49 66.04 0)
      (effects (font (size 1.27 1.27)) (justify left bottom) hide)
    )
    (property "Author" "Antmicro" (at 219.71 66.04 0)
      (effects (font (size 1.27 1.27) (thickness 0.15)) (justify left bottom) hide)
    )
    (pin "1")
    (pin "2")
    (instances
      (project "thunderbolt-pcie-adapter"
        (path ""
          (reference "R6") (unit 1)
        )
      )
    )
  )

  (symbol (lib_id "antmicropower:PWR_FLAG") (at 72.39 26.67 0) (unit 1)
    (in_bom yes) (on_board yes) (dnp no)
    (property "Reference" "#FLG06" (at 72.39 24.765 0)
      (effects (font (size 1.27 1.27)) hide)
    )
    (property "Value" "PWR_FLAG" (at 72.39 22.86 0)
      (effects (font (size 1.27 1.27)))
    )
    (property "Footprint" "" (at 72.39 26.67 0)
      (effects (font (size 1.27 1.27)) hide)
    )
    (property "Datasheet" "" (at 72.39 26.67 0)
      (effects (font (size 1.27 1.27)) hide)
    )
    (pin "1")
    (instances
      (project "thunderbolt-pcie-adapter"
        (path ""
          (reference "#FLG06") (unit 1)
        )
      )
    )
  )

  (symbol (lib_id "antmicroResistors0603:R_0R_0603") (at 180.34 43.18 0) (unit 1)
    (in_bom yes) (on_board yes) (dnp no)
    (property "Reference" "R41" (at 182.88 41.275 0)
      (effects (font (size 1.27 1.27) (thickness 0.15)))
    )
    (property "Value" "R_0R_0603" (at 200.66 55.88 0)
      (effects (font (size 1.27 1.27) (thickness 0.15)) (justify left bottom) hide)
    )
    (property "Footprint" "antmicro-footprints:R_0603_1608Metric" (at 200.66 58.42 0)
      (effects (font (size 1.27 1.27) (thickness 0.15)) (justify left bottom) hide)
    )
    (property "Datasheet" "https://www.bourns.com/docs/product-datasheets/cr.pdf?sfvrsn=574d41f6_14" (at 200.66 60.96 0)
      (effects (font (size 1.27 1.27) (thickness 0.15)) (justify left bottom) hide)
    )
    (property "MPN" "CR0603-J/-000ELF" (at 200.66 63.5 0)
      (effects (font (size 1.27 1.27) (thickness 0.15)) (justify left bottom) hide)
    )
    (property "Manufacturer" "Bourns" (at 200.66 66.04 0)
      (effects (font (size 1.27 1.27) (thickness 0.15)) (justify left bottom) hide)
    )
    (property "License" "Apache-2.0" (at 200.66 68.58 0)
      (effects (font (size 1.27 1.27) (thickness 0.15)) (justify left bottom) hide)
    )
    (property "Val" "0R" (at 181.61 43.815 0)
      (effects (font (size 1.27 1.27) (thickness 0.15)) (justify left bottom))
    )
    (property "Tolerance" "~" (at 200.66 53.34 0)
      (effects (font (size 1.27 1.27)) (justify left bottom) hide)
    )
    (property "Current" "1A" (at 200.66 73.66 0)
      (effects (font (size 1.27 1.27) (thickness 0.15)) (justify left bottom) hide)
    )
    (property "Author" "Antmicro" (at 200.66 71.12 0)
      (effects (font (size 1.27 1.27) (thickness 0.15)) (justify left bottom) hide)
    )
    (pin "1")
    (pin "2")
    (instances
      (project "thunderbolt-pcie-adapter"
        (path ""
          (reference "R41") (unit 1)
        )
      )
    )
  )

  (symbol (lib_id "antmicropower:GND") (at 278.13 76.2 0) (unit 1)
    (in_bom yes) (on_board yes) (dnp no)
    (property "Reference" "#PWR037" (at 278.13 82.55 0)
      (effects (font (size 1.27 1.27)) hide)
    )
    (property "Value" "GND" (at 276.225 80.645 0)
      (effects (font (size 1.27 1.27) (thickness 0.15)) (justify left bottom))
    )
    (property "Footprint" "" (at 278.13 76.2 0)
      (effects (font (size 1.27 1.27) (thickness 0.15)) (justify left bottom) hide)
    )
    (property "Datasheet" "" (at 278.13 76.2 0)
      (effects (font (size 1.27 1.27) (thickness 0.15)) (justify left bottom) hide)
    )
    (property "Author" "Antmicro" (at 287.02 83.82 0)
      (effects (font (size 1.27 1.27) (thickness 0.15)) (justify left bottom) hide)
    )
    (property "License" "Apache-2.0" (at 287.02 86.36 0)
      (effects (font (size 1.27 1.27) (thickness 0.15)) (justify left bottom) hide)
    )
    (pin "1")
    (instances
      (project "thunderbolt-pcie-adapter"
        (path ""
          (reference "#PWR037") (unit 1)
        )
      )
    )
  )

  (symbol (lib_id "antmicroLEDIndicationDiscrete:LED_G_0603_KP-1608CGCK") (at 331.47 162.56 90) (unit 1)
    (in_bom yes) (on_board yes) (dnp no)
    (property "Reference" "D3" (at 328.295 161.925 90)
      (effects (font (size 1.27 1.27) (thickness 0.15)) (justify left))
    )
    (property "Value" "LED_G_0603_KP-1608CGCK" (at 339.09 139.7 0)
      (effects (font (size 1.27 1.27) (thickness 0.15)) (justify left bottom) hide)
    )
    (property "Footprint" "antmicro-footprints:LED_0603_1608Metric_G" (at 341.63 139.7 0)
      (effects (font (size 1.27 1.27) (thickness 0.15)) (justify left bottom) hide)
    )
    (property "Datasheet" "http://www.kingbright.com/attachments/file/psearch//000/00/00/KP-1608CGCK(Ver.23B).pdf" (at 344.17 139.7 0)
      (effects (font (size 1.27 1.27) (thickness 0.15)) (justify left bottom) hide)
    )
    (property "MPN" "KP-1608CGCK" (at 346.71 139.7 0)
      (effects (font (size 1.27 1.27) (thickness 0.15)) (justify left bottom) hide)
    )
    (property "Manufacturer" "Kingbright" (at 349.25 139.7 0)
      (effects (font (size 1.27 1.27) (thickness 0.15)) (justify left bottom) hide)
    )
    (property "License" "Apache-2.0" (at 354.33 139.7 0)
      (effects (font (size 1.27 1.27) (thickness 0.15)) (justify left bottom) hide)
    )
    (property "Author" "Antmicro" (at 351.79 139.7 0)
      (effects (font (size 1.27 1.27) (thickness 0.15)) (justify left bottom) hide)
    )
    (property "Color" "Green" (at 330.835 163.195 90)
      (effects (font (size 1.27 1.27)) (justify left bottom))
    )
    (pin "1")
    (pin "2")
    (instances
      (project "thunderbolt-pcie-adapter"
        (path ""
          (reference "D3") (unit 1)
        )
      )
    )
  )

  (symbol (lib_id "antmicroCapacitors0402:C_1u_0402") (at 278.13 72.39 90) (unit 1)
    (in_bom yes) (on_board yes) (dnp no) (fields_autoplaced)
    (property "Reference" "C25" (at 280.67 68.5736 90)
      (effects (font (size 1.27 1.27) (thickness 0.15)) (justify right))
    )
    (property "Value" "C_1u_0402" (at 288.29 52.07 0)
      (effects (font (size 1.27 1.27) (thickness 0.15)) (justify left bottom) hide)
    )
    (property "Footprint" "antmicro-footprints:C_0402_1005Metric" (at 290.83 52.07 0)
      (effects (font (size 1.27 1.27) (thickness 0.15)) (justify left bottom) hide)
    )
    (property "Datasheet" "https://product.tdk.com/en/search/capacitor/ceramic/mlcc/info?part_no=C1005X6S1A105K050BC" (at 293.37 52.07 0)
      (effects (font (size 1.27 1.27) (thickness 0.15)) (justify left bottom) hide)
    )
    (property "MPN" "C1005X6S1A105K050BC" (at 295.91 52.07 0)
      (effects (font (size 1.27 1.27) (thickness 0.15)) (justify left bottom) hide)
    )
    (property "Manufacturer" "TDK" (at 298.45 52.07 0)
      (effects (font (size 1.27 1.27) (thickness 0.15)) (justify left bottom) hide)
    )
    (property "License" "Apache-2.0" (at 300.99 52.07 0)
      (effects (font (size 1.27 1.27) (thickness 0.15)) (justify left bottom) hide)
    )
    (property "Val" "1u" (at 280.67 71.1136 90)
      (effects (font (size 1.27 1.27) (thickness 0.15)) (justify right))
    )
    (property "Voltage" "" (at 306.07 52.07 0)
      (effects (font (size 1.27 1.27)) (justify left bottom) hide)
    )
    (property "Dielectric" "" (at 308.61 52.07 0)
      (effects (font (size 1.27 1.27)) (justify left bottom) hide)
    )
    (property "Author" "Antmicro" (at 303.53 52.07 0)
      (effects (font (size 1.27 1.27) (thickness 0.15)) (justify left bottom) hide)
    )
    (pin "1")
    (pin "2")
    (instances
      (project "thunderbolt-pcie-adapter"
        (path ""
          (reference "C25") (unit 1)
        )
      )
    )
  )

  (symbol (lib_id "antmicropower:GND") (at 134.62 170.18 0) (unit 1)
    (in_bom yes) (on_board yes) (dnp no)
    (property "Reference" "#PWR028" (at 134.62 176.53 0)
      (effects (font (size 1.27 1.27)) hide)
    )
    (property "Value" "GND" (at 132.715 174.625 0)
      (effects (font (size 1.27 1.27) (thickness 0.15)) (justify left bottom))
    )
    (property "Footprint" "" (at 134.62 170.18 0)
      (effects (font (size 1.27 1.27) (thickness 0.15)) (justify left bottom) hide)
    )
    (property "Datasheet" "" (at 134.62 170.18 0)
      (effects (font (size 1.27 1.27) (thickness 0.15)) (justify left bottom) hide)
    )
    (property "Author" "Antmicro" (at 143.51 177.8 0)
      (effects (font (size 1.27 1.27) (thickness 0.15)) (justify left bottom) hide)
    )
    (property "License" "Apache-2.0" (at 143.51 180.34 0)
      (effects (font (size 1.27 1.27) (thickness 0.15)) (justify left bottom) hide)
    )
    (pin "1")
    (instances
      (project "thunderbolt-pcie-adapter"
        (path ""
          (reference "#PWR028") (unit 1)
        )
      )
    )
  )

  (symbol (lib_id "antmicroCapacitors0402:C_22n_0402") (at 119.38 237.49 270) (mirror x) (unit 1)
    (in_bom yes) (on_board yes) (dnp no)
    (property "Reference" "C19" (at 116.84 233.6736 90)
      (effects (font (size 1.27 1.27) (thickness 0.15)) (justify right))
    )
    (property "Value" "C_22n_0402" (at 109.22 217.17 0)
      (effects (font (size 1.27 1.27) (thickness 0.15)) (justify left bottom) hide)
    )
    (property "Footprint" "antmicro-footprints:C_0402_1005Metric" (at 106.68 217.17 0)
      (effects (font (size 1.27 1.27) (thickness 0.15)) (justify left bottom) hide)
    )
    (property "Datasheet" "https://www.murata.com/products/productdetail?partno=GCM155R71H223MA55%23" (at 104.14 217.17 0)
      (effects (font (size 1.27 1.27) (thickness 0.15)) (justify left bottom) hide)
    )
    (property "MPN" "GCM155R71H223MA55D" (at 101.6 217.17 0)
      (effects (font (size 1.27 1.27) (thickness 0.15)) (justify left bottom) hide)
    )
    (property "Manufacturer" "Murata" (at 99.06 217.17 0)
      (effects (font (size 1.27 1.27) (thickness 0.15)) (justify left bottom) hide)
    )
    (property "License" "Apache-2.0" (at 96.52 217.17 0)
      (effects (font (size 1.27 1.27) (thickness 0.15)) (justify left bottom) hide)
    )
    (property "Val" "22n" (at 116.84 236.2136 90)
      (effects (font (size 1.27 1.27) (thickness 0.15)) (justify right))
    )
    (property "Voltage" "" (at 91.44 217.17 0)
      (effects (font (size 1.27 1.27)) (justify left bottom) hide)
    )
    (property "Dielectric" "" (at 88.9 217.17 0)
      (effects (font (size 1.27 1.27)) (justify left bottom) hide)
    )
    (property "Author" "Antmicro" (at 93.98 217.17 0)
      (effects (font (size 1.27 1.27) (thickness 0.15)) (justify left bottom) hide)
    )
    (pin "1")
    (pin "2")
    (instances
      (project "thunderbolt-pcie-adapter"
        (path ""
          (reference "C19") (unit 1)
        )
      )
    )
  )

  (symbol (lib_id "antmicroCapacitors0402:C_2u2_0402") (at 135.89 55.88 0) (unit 1)
    (in_bom yes) (on_board yes) (dnp no)
    (property "Reference" "C35" (at 141.605 54.61 0)
      (effects (font (size 1.27 1.27) (thickness 0.15)))
    )
    (property "Value" "C_2u2_0402" (at 156.21 66.04 0)
      (effects (font (size 1.27 1.27) (thickness 0.15)) (justify left bottom) hide)
    )
    (property "Footprint" "antmicro-footprints:C_0402_1005Metric" (at 156.21 68.58 0)
      (effects (font (size 1.27 1.27) (thickness 0.15)) (justify left bottom) hide)
    )
    (property "Datasheet" "https://product.tdk.com/en/search/capacitor/ceramic/mlcc/info?part_no=C1005X5R1A225K050BC" (at 156.21 71.12 0)
      (effects (font (size 1.27 1.27) (thickness 0.15)) (justify left bottom) hide)
    )
    (property "MPN" "C1005X5R1A225K050BC" (at 156.21 73.66 0)
      (effects (font (size 1.27 1.27) (thickness 0.15)) (justify left bottom) hide)
    )
    (property "Manufacturer" "TDK" (at 156.21 76.2 0)
      (effects (font (size 1.27 1.27) (thickness 0.15)) (justify left bottom) hide)
    )
    (property "License" "Apache-2.0" (at 156.21 78.74 0)
      (effects (font (size 1.27 1.27) (thickness 0.15)) (justify left bottom) hide)
    )
    (property "Val" "2u2" (at 139.7 57.785 0)
      (effects (font (size 1.27 1.27) (thickness 0.15)) (justify left bottom))
    )
    (property "Voltage" "" (at 156.21 83.82 0)
      (effects (font (size 1.27 1.27)) (justify left bottom) hide)
    )
    (property "Dielectric" "" (at 156.21 86.36 0)
      (effects (font (size 1.27 1.27)) (justify left bottom) hide)
    )
    (property "Author" "Antmicro" (at 156.21 81.28 0)
      (effects (font (size 1.27 1.27) (thickness 0.15)) (justify left bottom) hide)
    )
    (pin "1")
    (pin "2")
    (instances
      (project "thunderbolt-pcie-adapter"
        (path ""
          (reference "C35") (unit 1)
        )
      )
    )
  )

  (symbol (lib_id "antmicropower:GND") (at 93.98 215.9 0) (unit 1)
    (in_bom yes) (on_board yes) (dnp no)
    (property "Reference" "#PWR0169" (at 93.98 222.25 0)
      (effects (font (size 1.27 1.27)) hide)
    )
    (property "Value" "GND" (at 92.075 220.345 0)
      (effects (font (size 1.27 1.27) (thickness 0.15)) (justify left bottom))
    )
    (property "Footprint" "" (at 93.98 215.9 0)
      (effects (font (size 1.27 1.27) (thickness 0.15)) (justify left bottom) hide)
    )
    (property "Datasheet" "" (at 93.98 215.9 0)
      (effects (font (size 1.27 1.27) (thickness 0.15)) (justify left bottom) hide)
    )
    (property "Author" "Antmicro" (at 102.87 223.52 0)
      (effects (font (size 1.27 1.27) (thickness 0.15)) (justify left bottom) hide)
    )
    (property "License" "Apache-2.0" (at 102.87 226.06 0)
      (effects (font (size 1.27 1.27) (thickness 0.15)) (justify left bottom) hide)
    )
    (pin "1")
    (instances
      (project "thunderbolt-pcie-adapter"
        (path ""
          (reference "#PWR0169") (unit 1)
        )
      )
    )
  )

  (symbol (lib_id "antmicropower:GND") (at 148.59 50.8 90) (unit 1)
    (in_bom yes) (on_board yes) (dnp no)
    (property "Reference" "#PWR067" (at 154.94 50.8 0)
      (effects (font (size 1.27 1.27)) hide)
    )
    (property "Value" "GND" (at 153.035 52.705 0)
      (effects (font (size 1.27 1.27) (thickness 0.15)) (justify left bottom))
    )
    (property "Footprint" "" (at 148.59 50.8 0)
      (effects (font (size 1.27 1.27) (thickness 0.15)) (justify left bottom) hide)
    )
    (property "Datasheet" "" (at 148.59 50.8 0)
      (effects (font (size 1.27 1.27) (thickness 0.15)) (justify left bottom) hide)
    )
    (property "Author" "Antmicro" (at 156.21 41.91 0)
      (effects (font (size 1.27 1.27) (thickness 0.15)) (justify left bottom) hide)
    )
    (property "License" "Apache-2.0" (at 158.75 41.91 0)
      (effects (font (size 1.27 1.27) (thickness 0.15)) (justify left bottom) hide)
    )
    (pin "1")
    (instances
      (project "thunderbolt-pcie-adapter"
        (path ""
          (reference "#PWR067") (unit 1)
        )
      )
    )
  )

  (symbol (lib_id "antmicroResistors0402:R_5k1_0402") (at 158.75 83.82 90) (unit 1)
    (in_bom yes) (on_board yes) (dnp no)
    (property "Reference" "R38" (at 153.67 80.01 90)
      (effects (font (size 1.27 1.27) (thickness 0.15)) (justify right))
    )
    (property "Value" "R_5k1_0402" (at 171.45 63.5 0)
      (effects (font (size 1.27 1.27) (thickness 0.15)) (justify left bottom) hide)
    )
    (property "Footprint" "antmicro-footprints:R_0402_1005Metric" (at 173.99 63.5 0)
      (effects (font (size 1.27 1.27) (thickness 0.15)) (justify left bottom) hide)
    )
    (property "Datasheet" "https://www.bourns.com/docs/product-datasheets/cr.pdf" (at 176.53 63.5 0)
      (effects (font (size 1.27 1.27) (thickness 0.15)) (justify left bottom) hide)
    )
    (property "MPN" "CR0402-FX-5101GLF" (at 179.07 63.5 0)
      (effects (font (size 1.27 1.27) (thickness 0.15)) (justify left bottom) hide)
    )
    (property "Manufacturer" "Bourns" (at 181.61 63.5 0)
      (effects (font (size 1.27 1.27) (thickness 0.15)) (justify left bottom) hide)
    )
    (property "License" "Apache-2.0" (at 184.15 63.5 0)
      (effects (font (size 1.27 1.27) (thickness 0.15)) (justify left bottom) hide)
    )
    (property "Val" "5k1" (at 157.48 81.28 90)
      (effects (font (size 1.27 1.27) (thickness 0.15)) (justify left bottom))
    )
    (property "Tolerance" "1%" (at 168.91 63.5 0)
      (effects (font (size 1.27 1.27)) (justify left bottom) hide)
    )
    (property "Author" "Antmicro" (at 186.69 63.5 0)
      (effects (font (size 1.27 1.27) (thickness 0.15)) (justify left bottom) hide)
    )
    (pin "1")
    (pin "2")
    (instances
      (project "thunderbolt-pcie-adapter"
        (path ""
          (reference "R38") (unit 1)
        )
      )
    )
  )

  (symbol (lib_id "antmicroPMICORControllersIdealDiodes:DZDH0401DW") (at 260.35 158.75 0) (unit 1)
    (in_bom yes) (on_board yes) (dnp no) (fields_autoplaced)
    (property "Reference" "Q3" (at 268.605 152.4 0)
      (effects (font (size 1.524 1.524)))
    )
    (property "Value" "DZDH0401DW" (at 290.83 166.37 0)
      (effects (font (size 1.27 1.27) (thickness 0.15)) (justify left bottom) hide)
    )
    (property "Footprint" "antmicro-footprints:SOT-363" (at 290.83 168.91 0)
      (effects (font (size 1.27 1.27) (thickness 0.15)) (justify left bottom) hide)
    )
    (property "Datasheet" "https://www.mouser.com/datasheet/2/115/DIOD_S_A0011803041_1-2543705.pdf" (at 290.83 171.45 0)
      (effects (font (size 1.27 1.27) (thickness 0.15)) (justify left bottom) hide)
    )
    (property "MPN" "DZDH0401DW" (at 268.605 154.94 0)
      (effects (font (size 1.27 1.27) (thickness 0.15)))
    )
    (property "Manufacturer" "Diodes Incorporated" (at 290.83 176.53 0)
      (effects (font (size 1.27 1.27) (thickness 0.15)) (justify left bottom) hide)
    )
    (property "Author" "Antmicro" (at 290.83 179.07 0)
      (effects (font (size 1.27 1.27) (thickness 0.15)) (justify left bottom) hide)
    )
    (property "License" "Apache-2.0" (at 290.83 181.61 0)
      (effects (font (size 1.27 1.27) (thickness 0.15)) (justify left bottom) hide)
    )
    (pin "2")
    (pin "3")
    (pin "4")
    (pin "6")
    (instances
      (project "thunderbolt-pcie-adapter"
        (path ""
          (reference "Q3") (unit 1)
        )
      )
    )
  )

  (symbol (lib_id "antmicroCapacitors0603:C_22u_16V_0603") (at 59.69 266.7 90) (unit 1)
    (in_bom yes) (on_board yes) (dnp no)
    (property "Reference" "C122" (at 60.325 262.255 90)
      (effects (font (size 1.27 1.27) (thickness 0.15)) (justify right))
    )
    (property "Value" "C_22u_16V_0603" (at 69.85 246.38 0)
      (effects (font (size 1.27 1.27) (thickness 0.15)) (justify left bottom) hide)
    )
    (property "Footprint" "antmicro-footprints:C_0603_1608Metric" (at 72.39 246.38 0)
      (effects (font (size 1.27 1.27) (thickness 0.15)) (justify left bottom) hide)
    )
    (property "Datasheet" "https://product.samsungsem.com/mlcc/CL10A226MO7JZN.do" (at 74.93 246.38 0)
      (effects (font (size 1.27 1.27) (thickness 0.15)) (justify left bottom) hide)
    )
    (property "MPN" "CL10A226MO7JZNC" (at 77.47 246.38 0)
      (effects (font (size 1.27 1.27) (thickness 0.15)) (justify left bottom) hide)
    )
    (property "Manufacturer" "Samsung Electro-Mechanics" (at 80.01 246.38 0)
      (effects (font (size 1.27 1.27) (thickness 0.15)) (justify left bottom) hide)
    )
    (property "License" "Apache-2.0" (at 82.55 246.38 0)
      (effects (font (size 1.27 1.27) (thickness 0.15)) (justify left bottom) hide)
    )
    (property "Val" "22u" (at 65.405 263.525 90)
      (effects (font (size 1.27 1.27) (thickness 0.15)) (justify left bottom))
    )
    (property "Voltage" "16V" (at 87.63 246.38 0)
      (effects (font (size 1.27 1.27)) (justify left bottom) hide)
    )
    (property "Dielectric" "" (at 90.17 246.38 0)
      (effects (font (size 1.27 1.27)) (justify left bottom) hide)
    )
    (property "Author" "Antmicro" (at 85.09 246.38 0)
      (effects (font (size 1.27 1.27) (thickness 0.15)) (justify left bottom) hide)
    )
    (pin "1")
    (pin "2")
    (instances
      (project "thunderbolt-pcie-adapter"
        (path ""
          (reference "C122") (unit 1)
        )
      )
    )
  )

  (symbol (lib_id "antmicropower:GND") (at 146.05 129.54 90) (unit 1)
    (in_bom yes) (on_board yes) (dnp no)
    (property "Reference" "#PWR048" (at 152.4 129.54 0)
      (effects (font (size 1.27 1.27)) hide)
    )
    (property "Value" "GND" (at 150.495 131.445 0)
      (effects (font (size 1.27 1.27) (thickness 0.15)) (justify left bottom))
    )
    (property "Footprint" "" (at 146.05 129.54 0)
      (effects (font (size 1.27 1.27) (thickness 0.15)) (justify left bottom) hide)
    )
    (property "Datasheet" "" (at 146.05 129.54 0)
      (effects (font (size 1.27 1.27) (thickness 0.15)) (justify left bottom) hide)
    )
    (property "Author" "Antmicro" (at 153.67 120.65 0)
      (effects (font (size 1.27 1.27) (thickness 0.15)) (justify left bottom) hide)
    )
    (property "License" "Apache-2.0" (at 156.21 120.65 0)
      (effects (font (size 1.27 1.27) (thickness 0.15)) (justify left bottom) hide)
    )
    (pin "1")
    (instances
      (project "thunderbolt-pcie-adapter"
        (path ""
          (reference "#PWR048") (unit 1)
        )
      )
    )
  )

  (symbol (lib_id "antmicropower:GND") (at 119.38 238.76 0) (unit 1)
    (in_bom yes) (on_board yes) (dnp no)
    (property "Reference" "#PWR0172" (at 119.38 245.11 0)
      (effects (font (size 1.27 1.27)) hide)
    )
    (property "Value" "GND" (at 117.475 243.205 0)
      (effects (font (size 1.27 1.27) (thickness 0.15)) (justify left bottom))
    )
    (property "Footprint" "" (at 119.38 238.76 0)
      (effects (font (size 1.27 1.27) (thickness 0.15)) (justify left bottom) hide)
    )
    (property "Datasheet" "" (at 119.38 238.76 0)
      (effects (font (size 1.27 1.27) (thickness 0.15)) (justify left bottom) hide)
    )
    (property "Author" "Antmicro" (at 128.27 246.38 0)
      (effects (font (size 1.27 1.27) (thickness 0.15)) (justify left bottom) hide)
    )
    (property "License" "Apache-2.0" (at 128.27 248.92 0)
      (effects (font (size 1.27 1.27) (thickness 0.15)) (justify left bottom) hide)
    )
    (pin "1")
    (instances
      (project "thunderbolt-pcie-adapter"
        (path ""
          (reference "#PWR0172") (unit 1)
        )
      )
    )
  )

  (symbol (lib_id "antmicroTestPoints:TP_1mm_SMD") (at 134.62 234.95 0) (mirror y) (unit 1)
    (in_bom no) (on_board yes) (dnp no)
    (property "Reference" "TP5" (at 127 234.95 0)
      (effects (font (size 1.27 1.27) (thickness 0.15)) (justify right))
    )
    (property "Value" "TP_1mm_SMD" (at 119.38 242.57 0)
      (effects (font (size 1.27 1.27) (thickness 0.15)) (justify left bottom) hide)
    )
    (property "Footprint" "antmicro-footprints:TP_SMD_1mm" (at 119.38 245.11 0)
      (effects (font (size 1.27 1.27) (thickness 0.15)) (justify left bottom) hide)
    )
    (property "Datasheet" "" (at 116.84 247.65 0)
      (effects (font (size 1.27 1.27) (thickness 0.15)) (justify left bottom) hide)
    )
    (property "License" "Apache-2.0" (at 119.38 252.73 0)
      (effects (font (size 1.27 1.27) (thickness 0.15)) (justify left bottom) hide)
    )
    (property "Manufacturer" "" (at 134.62 234.95 0)
      (effects (font (size 1.27 1.27)) hide)
    )
    (property "MPN" "" (at 134.62 234.95 0)
      (effects (font (size 1.27 1.27)) hide)
    )
    (property "Author" "Antmicro" (at 119.38 250.19 0)
      (effects (font (size 1.27 1.27) (thickness 0.15)) (justify left bottom) hide)
    )
    (pin "1")
    (instances
      (project "thunderbolt-pcie-adapter"
        (path ""
          (reference "TP5") (unit 1)
        )
      )
    )
  )

  (symbol (lib_id "antmicroTransistorsBipolarSingle:BC817-25W") (at 62.23 242.57 0) (unit 1)
    (in_bom yes) (on_board yes) (dnp no) (fields_autoplaced)
    (property "Reference" "Q2" (at 71.12 241.3 0)
      (effects (font (size 1.27 1.27) (thickness 0.15)) (justify left))
    )
    (property "Value" "BC817-25W" (at 85.09 245.11 0)
      (effects (font (size 1.27 1.27) (thickness 0.15)) (justify left bottom) hide)
    )
    (property "Footprint" "antmicro-footprints:SOT-323" (at 85.09 247.65 0)
      (effects (font (size 1.27 1.27) (thickness 0.15)) (justify left bottom) hide)
    )
    (property "Datasheet" "https://assets.nexperia.com/documents/data-sheet/BC817W_SER.pdf" (at 85.09 250.19 0)
      (effects (font (size 1.27 1.27) (thickness 0.15)) (justify left bottom) hide)
    )
    (property "MPN" "BC817-25W,115" (at 71.12 243.84 0)
      (effects (font (size 1.27 1.27) (thickness 0.15)) (justify left))
    )
    (property "Manufacturer" "Nexperia" (at 85.09 255.27 0)
      (effects (font (size 1.27 1.27) (thickness 0.15)) (justify left bottom) hide)
    )
    (property "License" "Apache-2.0" (at 85.09 260.35 0)
      (effects (font (size 1.27 1.27) (thickness 0.15)) (justify left bottom) hide)
    )
    (property "Author" "Antmicro" (at 85.09 257.81 0)
      (effects (font (size 1.27 1.27) (thickness 0.15)) (justify left bottom) hide)
    )
    (pin "1")
    (pin "2")
    (pin "3")
    (instances
      (project "thunderbolt-pcie-adapter"
        (path ""
          (reference "Q2") (unit 1)
        )
      )
    )
  )

  (symbol (lib_id "antmicropower:GND") (at 358.14 76.2 0) (unit 1)
    (in_bom yes) (on_board yes) (dnp no)
    (property "Reference" "#PWR065" (at 358.14 82.55 0)
      (effects (font (size 1.27 1.27)) hide)
    )
    (property "Value" "GND" (at 356.235 80.645 0)
      (effects (font (size 1.27 1.27) (thickness 0.15)) (justify left bottom))
    )
    (property "Footprint" "" (at 358.14 76.2 0)
      (effects (font (size 1.27 1.27) (thickness 0.15)) (justify left bottom) hide)
    )
    (property "Datasheet" "" (at 358.14 76.2 0)
      (effects (font (size 1.27 1.27) (thickness 0.15)) (justify left bottom) hide)
    )
    (property "Author" "Antmicro" (at 367.03 83.82 0)
      (effects (font (size 1.27 1.27) (thickness 0.15)) (justify left bottom) hide)
    )
    (property "License" "Apache-2.0" (at 367.03 86.36 0)
      (effects (font (size 1.27 1.27) (thickness 0.15)) (justify left bottom) hide)
    )
    (pin "1")
    (instances
      (project "thunderbolt-pcie-adapter"
        (path ""
          (reference "#PWR065") (unit 1)
        )
      )
    )
  )

  (symbol (lib_id "antmicroCapacitorsmisc:C_22u_25V_0805") (at 161.29 52.07 90) (unit 1)
    (in_bom yes) (on_board yes) (dnp no) (fields_autoplaced)
    (property "Reference" "C42" (at 164.465 46.9836 90)
      (effects (font (size 1.27 1.27) (thickness 0.15)) (justify right))
    )
    (property "Value" "C_22u_25V_0805" (at 171.45 31.75 0)
      (effects (font (size 1.27 1.27) (thickness 0.15)) (justify left bottom) hide)
    )
    (property "Footprint" "antmicro-footprints:C_0805_2012Metric" (at 173.99 31.75 0)
      (effects (font (size 1.27 1.27) (thickness 0.15)) (justify left bottom) hide)
    )
    (property "Datasheet" "https://product.samsungsem.com/mlcc/CL21A226MAYNNN.do" (at 176.53 31.75 0)
      (effects (font (size 1.27 1.27) (thickness 0.15)) (justify left bottom) hide)
    )
    (property "MPN" "CL21A226MAYNNNE" (at 179.07 31.75 0)
      (effects (font (size 1.27 1.27) (thickness 0.15)) (justify left bottom) hide)
    )
    (property "Manufacturer" "Samsung Electro-Mechanics" (at 181.61 31.75 0)
      (effects (font (size 1.27 1.27) (thickness 0.15)) (justify left bottom) hide)
    )
    (property "License" "Apache-2.0" (at 184.15 31.75 0)
      (effects (font (size 1.27 1.27) (thickness 0.15)) (justify left bottom) hide)
    )
    (property "Val" "22u" (at 164.465 49.5236 90)
      (effects (font (size 1.27 1.27) (thickness 0.15)) (justify right))
    )
    (property "Voltage" "25V" (at 164.465 52.0636 90)
      (effects (font (size 1.27 1.27)) (justify right))
    )
    (property "Dielectric" "X5R" (at 191.77 31.75 0)
      (effects (font (size 1.27 1.27)) (justify left bottom) hide)
    )
    (property "Author" "Antmicro" (at 186.69 31.75 0)
      (effects (font (size 1.27 1.27) (thickness 0.15)) (justify left bottom) hide)
    )
    (pin "1")
    (pin "2")
    (instances
      (project "thunderbolt-pcie-adapter"
        (path ""
          (reference "C42") (unit 1)
        )
      )
    )
  )

  (symbol (lib_id "antmicropower:PWR_FLAG") (at 375.92 46.99 0) (unit 1)
    (in_bom yes) (on_board yes) (dnp no)
    (property "Reference" "#FLG0105" (at 375.92 45.085 0)
      (effects (font (size 1.27 1.27)) hide)
    )
    (property "Value" "PWR_FLAG" (at 375.92 43.18 0)
      (effects (font (size 1.27 1.27)))
    )
    (property "Footprint" "" (at 375.92 46.99 0)
      (effects (font (size 1.27 1.27)) hide)
    )
    (property "Datasheet" "" (at 375.92 46.99 0)
      (effects (font (size 1.27 1.27)) hide)
    )
    (pin "1")
    (instances
      (project "thunderbolt-pcie-adapter"
        (path ""
          (reference "#FLG0105") (unit 1)
        )
      )
    )
  )

  (symbol (lib_id "antmicroResistors0402:R_100k_0402") (at 278.13 170.18 90) (unit 1)
    (in_bom yes) (on_board yes) (dnp no) (fields_autoplaced)
    (property "Reference" "R95" (at 280.035 166.37 90)
      (effects (font (size 1.27 1.27) (thickness 0.15)) (justify right))
    )
    (property "Value" "R_100k_0402" (at 290.83 149.86 0)
      (effects (font (size 1.27 1.27) (thickness 0.15)) (justify left bottom) hide)
    )
    (property "Footprint" "antmicro-footprints:R_0402_1005Metric" (at 293.37 149.86 0)
      (effects (font (size 1.27 1.27) (thickness 0.15)) (justify left bottom) hide)
    )
    (property "Datasheet" "https://www.bourns.com/docs/product-datasheets/cr.pdf" (at 295.91 149.86 0)
      (effects (font (size 1.27 1.27) (thickness 0.15)) (justify left bottom) hide)
    )
    (property "MPN" "CR0402-FX-1003GLF" (at 298.45 149.86 0)
      (effects (font (size 1.27 1.27) (thickness 0.15)) (justify left bottom) hide)
    )
    (property "Manufacturer" "Bourns" (at 300.99 149.86 0)
      (effects (font (size 1.27 1.27) (thickness 0.15)) (justify left bottom) hide)
    )
    (property "License" "Apache-2.0" (at 303.53 149.86 0)
      (effects (font (size 1.27 1.27) (thickness 0.15)) (justify left bottom) hide)
    )
    (property "Author" "Antmicro" (at 306.07 149.86 0)
      (effects (font (size 1.27 1.27) (thickness 0.15)) (justify left bottom) hide)
    )
    (property "Val" "100k" (at 280.035 168.91 90)
      (effects (font (size 1.27 1.27) (thickness 0.15)) (justify right))
    )
    (property "Tolerance" "1%" (at 288.29 149.86 0)
      (effects (font (size 1.27 1.27)) (justify left bottom) hide)
    )
    (pin "1")
    (pin "2")
    (instances
      (project "thunderbolt-pcie-adapter"
        (path ""
          (reference "R95") (unit 1)
        )
      )
    )
  )

  (symbol (lib_id "antmicroResistors0402:R_10k_0402") (at 104.14 220.98 90) (unit 1)
    (in_bom yes) (on_board yes) (dnp no) (fields_autoplaced)
    (property "Reference" "R8" (at 106.68 217.17 90)
      (effects (font (size 1.27 1.27) (thickness 0.15)) (justify right))
    )
    (property "Value" "R_10k_0402" (at 116.84 200.66 0)
      (effects (font (size 1.27 1.27) (thickness 0.15)) (justify left bottom) hide)
    )
    (property "Footprint" "antmicro-footprints:R_0402_1005Metric" (at 119.38 200.66 0)
      (effects (font (size 1.27 1.27) (thickness 0.15)) (justify left bottom) hide)
    )
    (property "Datasheet" "https://www.bourns.com/docs/product-datasheets/cr.pdf" (at 121.92 200.66 0)
      (effects (font (size 1.27 1.27) (thickness 0.15)) (justify left bottom) hide)
    )
    (property "MPN" "CR0402-FX-1002GLF" (at 124.46 200.66 0)
      (effects (font (size 1.27 1.27) (thickness 0.15)) (justify left bottom) hide)
    )
    (property "Manufacturer" "Bourns" (at 127 200.66 0)
      (effects (font (size 1.27 1.27) (thickness 0.15)) (justify left bottom) hide)
    )
    (property "License" "Apache-2.0" (at 129.54 200.66 0)
      (effects (font (size 1.27 1.27) (thickness 0.15)) (justify left bottom) hide)
    )
    (property "Val" "10k" (at 106.68 219.71 90)
      (effects (font (size 1.27 1.27) (thickness 0.15)) (justify right))
    )
    (property "Tolerance" "1%" (at 114.3 200.66 0)
      (effects (font (size 1.27 1.27)) (justify left bottom) hide)
    )
    (property "Author" "Antmicro" (at 132.08 200.66 0)
      (effects (font (size 1.27 1.27) (thickness 0.15)) (justify left bottom) hide)
    )
    (pin "1")
    (pin "2")
    (instances
      (project "thunderbolt-pcie-adapter"
        (path ""
          (reference "R8") (unit 1)
        )
      )
    )
  )

  (symbol (lib_id "antmicropower:GND") (at 52.07 48.26 0) (unit 1)
    (in_bom yes) (on_board yes) (dnp no)
    (property "Reference" "#PWR016" (at 52.07 54.61 0)
      (effects (font (size 1.27 1.27)) hide)
    )
    (property "Value" "GND" (at 50.165 52.705 0)
      (effects (font (size 1.27 1.27) (thickness 0.15)) (justify left bottom))
    )
    (property "Footprint" "" (at 52.07 48.26 0)
      (effects (font (size 1.27 1.27) (thickness 0.15)) (justify left bottom) hide)
    )
    (property "Datasheet" "" (at 52.07 48.26 0)
      (effects (font (size 1.27 1.27) (thickness 0.15)) (justify left bottom) hide)
    )
    (property "Author" "Antmicro" (at 60.96 55.88 0)
      (effects (font (size 1.27 1.27) (thickness 0.15)) (justify left bottom) hide)
    )
    (property "License" "Apache-2.0" (at 60.96 58.42 0)
      (effects (font (size 1.27 1.27) (thickness 0.15)) (justify left bottom) hide)
    )
    (pin "1")
    (instances
      (project "thunderbolt-pcie-adapter"
        (path ""
          (reference "#PWR016") (unit 1)
        )
      )
    )
  )

  (symbol (lib_id "antmicroCapacitorsmisc:C_10u_0805_35V") (at 36.83 214.63 90) (unit 1)
    (in_bom yes) (on_board yes) (dnp no)
    (property "Reference" "C7" (at 30.48 210.185 90)
      (effects (font (size 1.27 1.27) (thickness 0.15)) (justify right))
    )
    (property "Value" "C_10u_0805_35V" (at 46.99 194.31 0)
      (effects (font (size 1.27 1.27) (thickness 0.15)) (justify left bottom) hide)
    )
    (property "Footprint" "antmicro-footprints:C_0805_2012Metric" (at 49.53 194.31 0)
      (effects (font (size 1.27 1.27) (thickness 0.15)) (justify left bottom) hide)
    )
    (property "Datasheet" "https://www.murata.com/products/productdetail?partno=GRM21BR6YA106KE43%23" (at 52.07 194.31 0)
      (effects (font (size 1.27 1.27) (thickness 0.15)) (justify left bottom) hide)
    )
    (property "MPN" "GRM21BR6YA106KE43L" (at 54.61 194.31 0)
      (effects (font (size 1.27 1.27) (thickness 0.15)) (justify left bottom) hide)
    )
    (property "Manufacturer" "Murata" (at 57.15 194.31 0)
      (effects (font (size 1.27 1.27) (thickness 0.15)) (justify left bottom) hide)
    )
    (property "License" "Apache-2.0" (at 59.69 194.31 0)
      (effects (font (size 1.27 1.27) (thickness 0.15)) (justify left bottom) hide)
    )
    (property "Val" "10u" (at 34.29 211.455 90)
      (effects (font (size 1.27 1.27) (thickness 0.15)) (justify left bottom))
    )
    (property "Voltage" "35V" (at 64.77 194.31 0)
      (effects (font (size 1.27 1.27)) (justify left bottom) hide)
    )
    (property "Dielectric" "" (at 67.31 194.31 0)
      (effects (font (size 1.27 1.27)) (justify left bottom) hide)
    )
    (property "Author" "Antmicro" (at 62.23 194.31 0)
      (effects (font (size 1.27 1.27) (thickness 0.15)) (justify left bottom) hide)
    )
    (pin "1")
    (pin "2")
    (instances
      (project "thunderbolt-pcie-adapter"
        (path ""
          (reference "C7") (unit 1)
        )
      )
    )
  )

  (symbol (lib_id "antmicroCapacitorsmisc:C_10u_0805_35V") (at 224.79 50.8 90) (unit 1)
    (in_bom yes) (on_board yes) (dnp no)
    (property "Reference" "C9" (at 218.44 46.355 90)
      (effects (font (size 1.27 1.27) (thickness 0.15)) (justify right))
    )
    (property "Value" "C_10u_0805_35V" (at 234.95 30.48 0)
      (effects (font (size 1.27 1.27) (thickness 0.15)) (justify left bottom) hide)
    )
    (property "Footprint" "antmicro-footprints:C_0805_2012Metric" (at 237.49 30.48 0)
      (effects (font (size 1.27 1.27) (thickness 0.15)) (justify left bottom) hide)
    )
    (property "Datasheet" "https://www.murata.com/products/productdetail?partno=GRM21BR6YA106KE43%23" (at 240.03 30.48 0)
      (effects (font (size 1.27 1.27) (thickness 0.15)) (justify left bottom) hide)
    )
    (property "MPN" "GRM21BR6YA106KE43L" (at 242.57 30.48 0)
      (effects (font (size 1.27 1.27) (thickness 0.15)) (justify left bottom) hide)
    )
    (property "Manufacturer" "Murata" (at 245.11 30.48 0)
      (effects (font (size 1.27 1.27) (thickness 0.15)) (justify left bottom) hide)
    )
    (property "License" "Apache-2.0" (at 247.65 30.48 0)
      (effects (font (size 1.27 1.27) (thickness 0.15)) (justify left bottom) hide)
    )
    (property "Val" "10u" (at 222.25 47.625 90)
      (effects (font (size 1.27 1.27) (thickness 0.15)) (justify left bottom))
    )
    (property "Voltage" "35V" (at 252.73 30.48 0)
      (effects (font (size 1.27 1.27)) (justify left bottom) hide)
    )
    (property "Dielectric" "" (at 255.27 30.48 0)
      (effects (font (size 1.27 1.27)) (justify left bottom) hide)
    )
    (property "Author" "Antmicro" (at 250.19 30.48 0)
      (effects (font (size 1.27 1.27) (thickness 0.15)) (justify left bottom) hide)
    )
    (pin "1")
    (pin "2")
    (instances
      (project "thunderbolt-pcie-adapter"
        (path ""
          (reference "C9") (unit 1)
        )
      )
    )
  )

  (symbol (lib_id "antmicropower:GND") (at 252.73 53.34 0) (unit 1)
    (in_bom yes) (on_board yes) (dnp no)
    (property "Reference" "#PWR019" (at 252.73 59.69 0)
      (effects (font (size 1.27 1.27)) hide)
    )
    (property "Value" "GND" (at 250.825 57.785 0)
      (effects (font (size 1.27 1.27) (thickness 0.15)) (justify left bottom))
    )
    (property "Footprint" "" (at 252.73 53.34 0)
      (effects (font (size 1.27 1.27) (thickness 0.15)) (justify left bottom) hide)
    )
    (property "Datasheet" "" (at 252.73 53.34 0)
      (effects (font (size 1.27 1.27) (thickness 0.15)) (justify left bottom) hide)
    )
    (property "Author" "Antmicro" (at 261.62 60.96 0)
      (effects (font (size 1.27 1.27) (thickness 0.15)) (justify left bottom) hide)
    )
    (property "License" "Apache-2.0" (at 261.62 63.5 0)
      (effects (font (size 1.27 1.27) (thickness 0.15)) (justify left bottom) hide)
    )
    (pin "1")
    (instances
      (project "thunderbolt-pcie-adapter"
        (path ""
          (reference "#PWR019") (unit 1)
        )
      )
    )
  )

  (symbol (lib_id "antmicropower:GND") (at 166.37 85.09 0) (unit 1)
    (in_bom yes) (on_board yes) (dnp no)
    (property "Reference" "#PWR095" (at 166.37 91.44 0)
      (effects (font (size 1.27 1.27)) hide)
    )
    (property "Value" "GND" (at 164.465 89.535 0)
      (effects (font (size 1.27 1.27) (thickness 0.15)) (justify left bottom))
    )
    (property "Footprint" "" (at 166.37 85.09 0)
      (effects (font (size 1.27 1.27) (thickness 0.15)) (justify left bottom) hide)
    )
    (property "Datasheet" "" (at 166.37 85.09 0)
      (effects (font (size 1.27 1.27) (thickness 0.15)) (justify left bottom) hide)
    )
    (property "Author" "Antmicro" (at 175.26 92.71 0)
      (effects (font (size 1.27 1.27) (thickness 0.15)) (justify left bottom) hide)
    )
    (property "License" "Apache-2.0" (at 175.26 95.25 0)
      (effects (font (size 1.27 1.27) (thickness 0.15)) (justify left bottom) hide)
    )
    (pin "1")
    (instances
      (project "thunderbolt-pcie-adapter"
        (path ""
          (reference "#PWR095") (unit 1)
        )
      )
    )
  )

  (symbol (lib_id "antmicroCapacitorsmisc:C_22u_25V_0805") (at 175.26 52.07 90) (unit 1)
    (in_bom yes) (on_board yes) (dnp no) (fields_autoplaced)
    (property "Reference" "C48" (at 177.8 46.9836 90)
      (effects (font (size 1.27 1.27) (thickness 0.15)) (justify right))
    )
    (property "Value" "C_22u_25V_0805" (at 185.42 31.75 0)
      (effects (font (size 1.27 1.27) (thickness 0.15)) (justify left bottom) hide)
    )
    (property "Footprint" "antmicro-footprints:C_0805_2012Metric" (at 187.96 31.75 0)
      (effects (font (size 1.27 1.27) (thickness 0.15)) (justify left bottom) hide)
    )
    (property "Datasheet" "https://product.samsungsem.com/mlcc/CL21A226MAYNNN.do" (at 190.5 31.75 0)
      (effects (font (size 1.27 1.27) (thickness 0.15)) (justify left bottom) hide)
    )
    (property "MPN" "CL21A226MAYNNNE" (at 193.04 31.75 0)
      (effects (font (size 1.27 1.27) (thickness 0.15)) (justify left bottom) hide)
    )
    (property "Manufacturer" "Samsung Electro-Mechanics" (at 195.58 31.75 0)
      (effects (font (size 1.27 1.27) (thickness 0.15)) (justify left bottom) hide)
    )
    (property "License" "Apache-2.0" (at 198.12 31.75 0)
      (effects (font (size 1.27 1.27) (thickness 0.15)) (justify left bottom) hide)
    )
    (property "Val" "22u" (at 177.8 49.5236 90)
      (effects (font (size 1.27 1.27) (thickness 0.15)) (justify right))
    )
    (property "Voltage" "25V" (at 177.8 52.0636 90)
      (effects (font (size 1.27 1.27)) (justify right))
    )
    (property "Dielectric" "X5R" (at 205.74 31.75 0)
      (effects (font (size 1.27 1.27)) (justify left bottom) hide)
    )
    (property "Author" "Antmicro" (at 200.66 31.75 0)
      (effects (font (size 1.27 1.27) (thickness 0.15)) (justify left bottom) hide)
    )
    (pin "1")
    (pin "2")
    (instances
      (project "thunderbolt-pcie-adapter"
        (path ""
          (reference "C48") (unit 1)
        )
      )
    )
  )

  (symbol (lib_id "antmicropower:GND") (at 375.92 76.2 0) (unit 1)
    (in_bom yes) (on_board yes) (dnp no)
    (property "Reference" "#PWR071" (at 375.92 82.55 0)
      (effects (font (size 1.27 1.27)) hide)
    )
    (property "Value" "GND" (at 374.015 80.645 0)
      (effects (font (size 1.27 1.27) (thickness 0.15)) (justify left bottom))
    )
    (property "Footprint" "" (at 375.92 76.2 0)
      (effects (font (size 1.27 1.27) (thickness 0.15)) (justify left bottom) hide)
    )
    (property "Datasheet" "" (at 375.92 76.2 0)
      (effects (font (size 1.27 1.27) (thickness 0.15)) (justify left bottom) hide)
    )
    (property "Author" "Antmicro" (at 384.81 83.82 0)
      (effects (font (size 1.27 1.27) (thickness 0.15)) (justify left bottom) hide)
    )
    (property "License" "Apache-2.0" (at 384.81 86.36 0)
      (effects (font (size 1.27 1.27) (thickness 0.15)) (justify left bottom) hide)
    )
    (pin "1")
    (instances
      (project "thunderbolt-pcie-adapter"
        (path ""
          (reference "#PWR071") (unit 1)
        )
      )
    )
  )

  (symbol (lib_id "antmicropower:GND") (at 241.3 233.68 0) (unit 1)
    (in_bom yes) (on_board yes) (dnp no)
    (property "Reference" "#PWR0184" (at 241.3 240.03 0)
      (effects (font (size 1.27 1.27)) hide)
    )
    (property "Value" "GND" (at 239.395 238.125 0)
      (effects (font (size 1.27 1.27) (thickness 0.15)) (justify left bottom))
    )
    (property "Footprint" "" (at 241.3 233.68 0)
      (effects (font (size 1.27 1.27) (thickness 0.15)) (justify left bottom) hide)
    )
    (property "Datasheet" "" (at 241.3 233.68 0)
      (effects (font (size 1.27 1.27) (thickness 0.15)) (justify left bottom) hide)
    )
    (property "Author" "Antmicro" (at 250.19 241.3 0)
      (effects (font (size 1.27 1.27) (thickness 0.15)) (justify left bottom) hide)
    )
    (property "License" "Apache-2.0" (at 250.19 243.84 0)
      (effects (font (size 1.27 1.27) (thickness 0.15)) (justify left bottom) hide)
    )
    (pin "1")
    (instances
      (project "thunderbolt-pcie-adapter"
        (path ""
          (reference "#PWR0184") (unit 1)
        )
      )
    )
  )

  (symbol (lib_id "antmicroDiodesZenerSingle:MM3Z3V3C") (at 262.89 67.31 90) (mirror x) (unit 1)
    (in_bom yes) (on_board yes) (dnp no) (fields_autoplaced)
    (property "Reference" "D1" (at 265.43 68.58 90)
      (effects (font (size 1.27 1.27) (thickness 0.15)) (justify right))
    )
    (property "Value" "MM3Z3V3C" (at 278.13 90.17 0)
      (effects (font (size 1.27 1.27) (thickness 0.15)) (justify left bottom) hide)
    )
    (property "Footprint" "antmicro-footprints:D_SOD-323F" (at 273.05 90.17 0)
      (effects (font (size 1.27 1.27) (thickness 0.15)) (justify left bottom) hide)
    )
    (property "Datasheet" "https://www.onsemi.com/download/data-sheet/pdf/mm3z9v1c-d.pdf" (at 275.59 90.17 0)
      (effects (font (size 1.27 1.27) (thickness 0.15)) (justify left bottom) hide)
    )
    (property "MPN" "MM3Z3V3C" (at 265.43 71.12 90)
      (effects (font (size 1.27 1.27) (thickness 0.15)) (justify right))
    )
    (property "Manufacturer" "ON Semiconductor" (at 280.67 90.17 0)
      (effects (font (size 1.27 1.27) (thickness 0.15)) (justify left bottom) hide)
    )
    (property "License" "Apache-2.0" (at 285.75 90.17 0)
      (effects (font (size 1.27 1.27) (thickness 0.15)) (justify left bottom) hide)
    )
    (property "Author" "Antmicro" (at 283.21 90.17 0)
      (effects (font (size 1.27 1.27) (thickness 0.15)) (justify left bottom) hide)
    )
    (pin "1")
    (pin "2")
    (instances
      (project "thunderbolt-pcie-adapter"
        (path ""
          (reference "D1") (unit 1)
        )
      )
    )
  )

  (symbol (lib_id "antmicropower:GND") (at 130.81 267.97 0) (mirror y) (unit 1)
    (in_bom yes) (on_board yes) (dnp no)
    (property "Reference" "#PWR0174" (at 130.81 274.32 0)
      (effects (font (size 1.27 1.27)) hide)
    )
    (property "Value" "GND" (at 132.715 272.415 0)
      (effects (font (size 1.27 1.27) (thickness 0.15)) (justify left bottom))
    )
    (property "Footprint" "" (at 130.81 267.97 0)
      (effects (font (size 1.27 1.27) (thickness 0.15)) (justify left bottom) hide)
    )
    (property "Datasheet" "" (at 130.81 267.97 0)
      (effects (font (size 1.27 1.27) (thickness 0.15)) (justify left bottom) hide)
    )
    (property "Author" "Antmicro" (at 121.92 275.59 0)
      (effects (font (size 1.27 1.27) (thickness 0.15)) (justify left bottom) hide)
    )
    (property "License" "Apache-2.0" (at 121.92 278.13 0)
      (effects (font (size 1.27 1.27) (thickness 0.15)) (justify left bottom) hide)
    )
    (pin "1")
    (instances
      (project "thunderbolt-pcie-adapter"
        (path ""
          (reference "#PWR0174") (unit 1)
        )
      )
    )
  )

  (symbol (lib_id "antmicroCapacitors0402:C_4u7_25V_0402") (at 52.07 48.26 90) (unit 1)
    (in_bom yes) (on_board yes) (dnp yes)
    (property "Reference" "C21" (at 53.975 44.4565 90)
      (effects (font (size 1.27 1.27) (thickness 0.15)) (justify right))
    )
    (property "Value" "C_4u7_25V_0402" (at 62.23 27.94 0)
      (effects (font (size 1.27 1.27) (thickness 0.15)) (justify left bottom) hide)
    )
    (property "Footprint" "antmicro-footprints:C_0402_1005Metric" (at 64.77 27.94 0)
      (effects (font (size 1.27 1.27) (thickness 0.15)) (justify left bottom) hide)
    )
    (property "Datasheet" "https://www.murata.com/products/productdetail?partno=GRM155C61E475ME15%23" (at 67.31 27.94 0)
      (effects (font (size 1.27 1.27) (thickness 0.15)) (justify left bottom) hide)
    )
    (property "MPN" "GRM155C61E475ME15J" (at 69.85 27.94 0)
      (effects (font (size 1.27 1.27) (thickness 0.15)) (justify left bottom) hide)
    )
    (property "Manufacturer" "Murata" (at 72.39 27.94 0)
      (effects (font (size 1.27 1.27) (thickness 0.15)) (justify left bottom) hide)
    )
    (property "License" "Apache-2.0" (at 74.93 27.94 0)
      (effects (font (size 1.27 1.27) (thickness 0.15)) (justify left bottom) hide)
    )
    (property "Val" "4u7" (at 53.975 46.9965 90)
      (effects (font (size 1.27 1.27) (thickness 0.15)) (justify right))
    )
    (property "Voltage" "25V" (at 55.245 46.9835 90)
      (effects (font (size 1.27 1.27)) (justify right) hide)
    )
    (property "Dielectric" "X5S" (at 82.55 27.94 0)
      (effects (font (size 1.27 1.27)) (justify left bottom) hide)
    )
    (property "Author" "Antmicro" (at 77.47 27.94 0)
      (effects (font (size 1.27 1.27) (thickness 0.15)) (justify left bottom) hide)
    )
    (pin "1")
    (pin "2")
    (instances
      (project "thunderbolt-pcie-adapter"
        (path ""
          (reference "C21") (unit 1)
        )
      )
    )
  )

  (symbol (lib_id "antmicroResistors0402:R_0R_0402") (at 66.04 99.06 0) (unit 1)
    (in_bom yes) (on_board yes) (dnp no)
    (property "Reference" "R18" (at 68.58 97.155 0)
      (effects (font (size 1.27 1.27) (thickness 0.15)))
    )
    (property "Value" "R_0R_0402" (at 86.36 111.76 0)
      (effects (font (size 1.27 1.27) (thickness 0.15)) (justify left bottom) hide)
    )
    (property "Footprint" "antmicro-footprints:R_0402_1005Metric" (at 86.36 114.3 0)
      (effects (font (size 1.27 1.27) (thickness 0.15)) (justify left bottom) hide)
    )
    (property "Datasheet" "https://industrial.panasonic.com/cdbs/www-data/pdf/RDA0000/AOA0000C301.pdf" (at 86.36 116.84 0)
      (effects (font (size 1.27 1.27) (thickness 0.15)) (justify left bottom) hide)
    )
    (property "MPN" "ERJ2GE0R00X" (at 86.36 119.38 0)
      (effects (font (size 1.27 1.27) (thickness 0.15)) (justify left bottom) hide)
    )
    (property "Manufacturer" "Panasonic" (at 86.36 121.92 0)
      (effects (font (size 1.27 1.27) (thickness 0.15)) (justify left bottom) hide)
    )
    (property "License" "Apache-2.0" (at 86.36 124.46 0)
      (effects (font (size 1.27 1.27) (thickness 0.15)) (justify left bottom) hide)
    )
    (property "Val" "0R" (at 71.12 98.425 0)
      (effects (font (size 1.27 1.27) (thickness 0.15)) (justify left bottom))
    )
    (property "Tolerance" "~" (at 86.36 109.22 0)
      (effects (font (size 1.27 1.27)) (justify left bottom) hide)
    )
    (property "Current" "1A" (at 86.36 129.54 0)
      (effects (font (size 1.27 1.27) (thickness 0.15)) (justify left bottom) hide)
    )
    (property "Author" "Antmicro" (at 86.36 127 0)
      (effects (font (size 1.27 1.27) (thickness 0.15)) (justify left bottom) hide)
    )
    (pin "1")
    (pin "2")
    (instances
      (project "thunderbolt-pcie-adapter"
        (path ""
          (reference "R18") (unit 1)
        )
      )
    )
  )

  (symbol (lib_id "antmicroCapacitors0603:C_22u_16V_0603") (at 228.6 219.71 90) (unit 1)
    (in_bom yes) (on_board yes) (dnp no) (fields_autoplaced)
    (property "Reference" "C46" (at 231.14 215.8936 90)
      (effects (font (size 1.27 1.27) (thickness 0.15)) (justify right))
    )
    (property "Value" "C_22u_16V_0603" (at 238.76 199.39 0)
      (effects (font (size 1.27 1.27) (thickness 0.15)) (justify left bottom) hide)
    )
    (property "Footprint" "antmicro-footprints:C_0603_1608Metric" (at 241.3 199.39 0)
      (effects (font (size 1.27 1.27) (thickness 0.15)) (justify left bottom) hide)
    )
    (property "Datasheet" "https://product.samsungsem.com/mlcc/CL10A226MO7JZN.do" (at 243.84 199.39 0)
      (effects (font (size 1.27 1.27) (thickness 0.15)) (justify left bottom) hide)
    )
    (property "MPN" "CL10A226MO7JZNC" (at 246.38 199.39 0)
      (effects (font (size 1.27 1.27) (thickness 0.15)) (justify left bottom) hide)
    )
    (property "Manufacturer" "Samsung Electro-Mechanics" (at 248.92 199.39 0)
      (effects (font (size 1.27 1.27) (thickness 0.15)) (justify left bottom) hide)
    )
    (property "License" "Apache-2.0" (at 251.46 199.39 0)
      (effects (font (size 1.27 1.27) (thickness 0.15)) (justify left bottom) hide)
    )
    (property "Val" "22u" (at 231.14 218.4336 90)
      (effects (font (size 1.27 1.27) (thickness 0.15)) (justify right))
    )
    (property "Voltage" "16V" (at 256.54 199.39 0)
      (effects (font (size 1.27 1.27)) (justify left bottom) hide)
    )
    (property "Dielectric" "" (at 259.08 199.39 0)
      (effects (font (size 1.27 1.27)) (justify left bottom) hide)
    )
    (property "Author" "Antmicro" (at 254 199.39 0)
      (effects (font (size 1.27 1.27) (thickness 0.15)) (justify left bottom) hide)
    )
    (pin "1")
    (pin "2")
    (instances
      (project "thunderbolt-pcie-adapter"
        (path ""
          (reference "C46") (unit 1)
        )
      )
    )
  )

  (symbol (lib_id "antmicroResistors0402:R_10k_0402") (at 241.3 233.68 90) (unit 1)
    (in_bom yes) (on_board yes) (dnp no) (fields_autoplaced)
    (property "Reference" "R44" (at 238.76 229.87 90)
      (effects (font (size 1.27 1.27) (thickness 0.15)) (justify left))
    )
    (property "Value" "R_10k_0402" (at 254 213.36 0)
      (effects (font (size 1.27 1.27) (thickness 0.15)) (justify left bottom) hide)
    )
    (property "Footprint" "antmicro-footprints:R_0402_1005Metric" (at 256.54 213.36 0)
      (effects (font (size 1.27 1.27) (thickness 0.15)) (justify left bottom) hide)
    )
    (property "Datasheet" "https://www.bourns.com/docs/product-datasheets/cr.pdf" (at 259.08 213.36 0)
      (effects (font (size 1.27 1.27) (thickness 0.15)) (justify left bottom) hide)
    )
    (property "MPN" "CR0402-FX-1002GLF" (at 261.62 213.36 0)
      (effects (font (size 1.27 1.27) (thickness 0.15)) (justify left bottom) hide)
    )
    (property "Manufacturer" "Bourns" (at 264.16 213.36 0)
      (effects (font (size 1.27 1.27) (thickness 0.15)) (justify left bottom) hide)
    )
    (property "License" "Apache-2.0" (at 266.7 213.36 0)
      (effects (font (size 1.27 1.27) (thickness 0.15)) (justify left bottom) hide)
    )
    (property "Val" "10k" (at 238.76 232.41 90)
      (effects (font (size 1.27 1.27) (thickness 0.15)) (justify left))
    )
    (property "Tolerance" "1%" (at 251.46 213.36 0)
      (effects (font (size 1.27 1.27)) (justify left bottom) hide)
    )
    (property "Author" "Antmicro" (at 269.24 213.36 0)
      (effects (font (size 1.27 1.27) (thickness 0.15)) (justify left bottom) hide)
    )
    (pin "1")
    (pin "2")
    (instances
      (project "thunderbolt-pcie-adapter"
        (path ""
          (reference "R44") (unit 1)
        )
      )
    )
  )

  (symbol (lib_id "antmicropower:GND") (at 184.15 85.09 0) (unit 1)
    (in_bom yes) (on_board yes) (dnp no)
    (property "Reference" "#PWR0167" (at 184.15 91.44 0)
      (effects (font (size 1.27 1.27)) hide)
    )
    (property "Value" "GND" (at 182.245 89.535 0)
      (effects (font (size 1.27 1.27) (thickness 0.15)) (justify left bottom))
    )
    (property "Footprint" "" (at 184.15 85.09 0)
      (effects (font (size 1.27 1.27) (thickness 0.15)) (justify left bottom) hide)
    )
    (property "Datasheet" "" (at 184.15 85.09 0)
      (effects (font (size 1.27 1.27) (thickness 0.15)) (justify left bottom) hide)
    )
    (property "Author" "Antmicro" (at 193.04 92.71 0)
      (effects (font (size 1.27 1.27) (thickness 0.15)) (justify left bottom) hide)
    )
    (property "License" "Apache-2.0" (at 193.04 95.25 0)
      (effects (font (size 1.27 1.27) (thickness 0.15)) (justify left bottom) hide)
    )
    (pin "1")
    (instances
      (project "thunderbolt-pcie-adapter"
        (path ""
          (reference "#PWR0167") (unit 1)
        )
      )
    )
  )

  (symbol (lib_id "antmicroResistors0402:R_10k_0402") (at 137.16 139.7 0) (unit 1)
    (in_bom yes) (on_board yes) (dnp no)
    (property "Reference" "R32" (at 139.7 137.795 0)
      (effects (font (size 1.27 1.27) (thickness 0.15)))
    )
    (property "Value" "R_10k_0402" (at 157.48 152.4 0)
      (effects (font (size 1.27 1.27) (thickness 0.15)) (justify left bottom) hide)
    )
    (property "Footprint" "antmicro-footprints:R_0402_1005Metric" (at 157.48 154.94 0)
      (effects (font (size 1.27 1.27) (thickness 0.15)) (justify left bottom) hide)
    )
    (property "Datasheet" "https://www.bourns.com/docs/product-datasheets/cr.pdf" (at 157.48 157.48 0)
      (effects (font (size 1.27 1.27) (thickness 0.15)) (justify left bottom) hide)
    )
    (property "MPN" "CR0402-FX-1002GLF" (at 157.48 160.02 0)
      (effects (font (size 1.27 1.27) (thickness 0.15)) (justify left bottom) hide)
    )
    (property "Manufacturer" "Bourns" (at 157.48 162.56 0)
      (effects (font (size 1.27 1.27) (thickness 0.15)) (justify left bottom) hide)
    )
    (property "License" "Apache-2.0" (at 157.48 165.1 0)
      (effects (font (size 1.27 1.27) (thickness 0.15)) (justify left bottom) hide)
    )
    (property "Val" "10k" (at 141.605 139.065 0)
      (effects (font (size 1.27 1.27) (thickness 0.15)) (justify left bottom))
    )
    (property "Tolerance" "1%" (at 157.48 149.86 0)
      (effects (font (size 1.27 1.27)) (justify left bottom) hide)
    )
    (property "Author" "Antmicro" (at 157.48 167.64 0)
      (effects (font (size 1.27 1.27) (thickness 0.15)) (justify left bottom) hide)
    )
    (pin "1")
    (pin "2")
    (instances
      (project "thunderbolt-pcie-adapter"
        (path ""
          (reference "R32") (unit 1)
        )
      )
    )
  )

  (symbol (lib_id "antmicroResistors0402:R_100k_0402") (at 358.14 170.18 90) (unit 1)
    (in_bom yes) (on_board yes) (dnp no) (fields_autoplaced)
    (property "Reference" "R96" (at 360.68 166.37 90)
      (effects (font (size 1.27 1.27) (thickness 0.15)) (justify right))
    )
    (property "Value" "R_100k_0402" (at 370.84 149.86 0)
      (effects (font (size 1.27 1.27) (thickness 0.15)) (justify left bottom) hide)
    )
    (property "Footprint" "antmicro-footprints:R_0402_1005Metric" (at 373.38 149.86 0)
      (effects (font (size 1.27 1.27) (thickness 0.15)) (justify left bottom) hide)
    )
    (property "Datasheet" "https://www.bourns.com/docs/product-datasheets/cr.pdf" (at 375.92 149.86 0)
      (effects (font (size 1.27 1.27) (thickness 0.15)) (justify left bottom) hide)
    )
    (property "MPN" "CR0402-FX-1003GLF" (at 378.46 149.86 0)
      (effects (font (size 1.27 1.27) (thickness 0.15)) (justify left bottom) hide)
    )
    (property "Manufacturer" "Bourns" (at 381 149.86 0)
      (effects (font (size 1.27 1.27) (thickness 0.15)) (justify left bottom) hide)
    )
    (property "License" "Apache-2.0" (at 383.54 149.86 0)
      (effects (font (size 1.27 1.27) (thickness 0.15)) (justify left bottom) hide)
    )
    (property "Author" "Antmicro" (at 386.08 149.86 0)
      (effects (font (size 1.27 1.27) (thickness 0.15)) (justify left bottom) hide)
    )
    (property "Val" "100k" (at 360.68 168.91 90)
      (effects (font (size 1.27 1.27) (thickness 0.15)) (justify right))
    )
    (property "Tolerance" "1%" (at 368.3 149.86 0)
      (effects (font (size 1.27 1.27)) (justify left bottom) hide)
    )
    (pin "1")
    (pin "2")
    (instances
      (project "thunderbolt-pcie-adapter"
        (path ""
          (reference "R96") (unit 1)
        )
      )
    )
  )

  (symbol (lib_id "antmicroResistors0603:R_0R_22.4A_0603") (at 293.37 146.05 0) (unit 1)
    (in_bom yes) (on_board yes) (dnp no)
    (property "Reference" "R98" (at 295.91 144.145 0)
      (effects (font (size 1.27 1.27) (thickness 0.15)))
    )
    (property "Value" "R_0R_22.4A_0603" (at 306.07 151.765 0)
      (effects (font (size 1.27 1.27) (thickness 0.15)) hide)
    )
    (property "Footprint" "antmicro-footprints:R_0603_1608Metric" (at 308.61 156.21 0)
      (effects (font (size 1.27 1.27) (thickness 0.15)) (justify left bottom) hide)
    )
    (property "Datasheet" "https://fscdn.rohm.com/en/products/databook/datasheet/passive/resistor/chip_resistor/pmr-jpw-e.pdf" (at 308.61 158.75 0)
      (effects (font (size 1.27 1.27) (thickness 0.15)) (justify left bottom) hide)
    )
    (property "MPN" "PMR03EZPJ000" (at 308.61 161.29 0)
      (effects (font (size 1.27 1.27) (thickness 0.15)) (justify left bottom) hide)
    )
    (property "Manufacturer" "ROHM Semiconductor" (at 308.61 163.83 0)
      (effects (font (size 1.27 1.27) (thickness 0.15)) (justify left bottom) hide)
    )
    (property "Val" "0R" (at 293.37 148.59 0)
      (effects (font (size 1.27 1.27) (thickness 0.15)))
    )
    (property "Max. Curr." "22.4A" (at 299.085 148.59 0)
      (effects (font (size 1.27 1.27) (thickness 0.15)))
    )
    (property "Author" "Antmicro" (at 308.61 168.91 0)
      (effects (font (size 1.27 1.27) (thickness 0.15)) (justify left bottom) hide)
    )
    (property "License" "Apache-2.0" (at 308.61 171.45 0)
      (effects (font (size 1.27 1.27) (thickness 0.15)) (justify left bottom) hide)
    )
    (property "Tolerance" "template_tolerance" (at 313.69 156.21 0)
      (effects (font (size 1.27 1.27)) (justify left bottom) hide)
    )
    (pin "2")
    (pin "1")
    (instances
      (project "thunderbolt-pcie-adapter"
        (path ""
          (reference "R98") (unit 1)
        )
      )
    )
  )

  (symbol (lib_id "antmicropower:GND") (at 73.66 215.9 0) (unit 1)
    (in_bom yes) (on_board yes) (dnp no)
    (property "Reference" "#PWR0162" (at 73.66 222.25 0)
      (effects (font (size 1.27 1.27)) hide)
    )
    (property "Value" "GND" (at 71.755 220.345 0)
      (effects (font (size 1.27 1.27) (thickness 0.15)) (justify left bottom))
    )
    (property "Footprint" "" (at 73.66 215.9 0)
      (effects (font (size 1.27 1.27) (thickness 0.15)) (justify left bottom) hide)
    )
    (property "Datasheet" "" (at 73.66 215.9 0)
      (effects (font (size 1.27 1.27) (thickness 0.15)) (justify left bottom) hide)
    )
    (property "Author" "Antmicro" (at 82.55 223.52 0)
      (effects (font (size 1.27 1.27) (thickness 0.15)) (justify left bottom) hide)
    )
    (property "License" "Apache-2.0" (at 82.55 226.06 0)
      (effects (font (size 1.27 1.27) (thickness 0.15)) (justify left bottom) hide)
    )
    (pin "1")
    (instances
      (project "thunderbolt-pcie-adapter"
        (path ""
          (reference "#PWR0162") (unit 1)
        )
      )
    )
  )

  (symbol (lib_id "antmicroTransistorsFETsMOSFETsSingle:SI7613DN-T1-GE3") (at 278.13 153.67 90) (unit 1)
    (in_bom yes) (on_board yes) (dnp no) (fields_autoplaced)
    (property "Reference" "Q5" (at 275.59 139.7 90)
      (effects (font (size 1.524 1.524)))
    )
    (property "Value" "SI7613DN-T1-GE3" (at 275.59 138.43 0)
      (effects (font (size 1.27 1.27) (thickness 0.15)) (justify left bottom) hide)
    )
    (property "Footprint" "antmicro-footprints:Vishay_PowerPAK_1212-8_Single" (at 276.86 138.43 0)
      (effects (font (size 1.27 1.27) (thickness 0.15)) (justify left bottom) hide)
    )
    (property "Datasheet" "https://www.vishay.com/docs/64809/si7613dn.pdf" (at 279.4 138.43 0)
      (effects (font (size 1.27 1.27) (thickness 0.15)) (justify left bottom) hide)
    )
    (property "MPN" "SI7613DN-T1-GE3" (at 275.59 142.24 90)
      (effects (font (size 1.27 1.27) (thickness 0.15)))
    )
    (property "Manufacturer" "Vishay" (at 285.75 138.43 0)
      (effects (font (size 1.27 1.27) (thickness 0.15)) (justify left bottom) hide)
    )
    (property "Author" "Antmicro" (at 288.29 138.43 0)
      (effects (font (size 1.27 1.27) (thickness 0.15)) (justify left bottom) hide)
    )
    (property "License" "Apache-2.0" (at 290.83 138.43 0)
      (effects (font (size 1.27 1.27) (thickness 0.15)) (justify left bottom) hide)
    )
    (pin "1")
    (pin "2")
    (pin "3")
    (pin "4")
    (pin "5")
    (instances
      (project "thunderbolt-pcie-adapter"
        (path ""
          (reference "Q5") (unit 1)
        )
      )
    )
  )

  (symbol (lib_id "antmicropower:PWR_FLAG") (at 66.04 48.26 0) (unit 1)
    (in_bom yes) (on_board yes) (dnp no)
    (property "Reference" "#FLG05" (at 66.04 46.355 0)
      (effects (font (size 1.27 1.27)) hide)
    )
    (property "Value" "PWR_FLAG" (at 66.04 44.45 0)
      (effects (font (size 1.27 1.27)))
    )
    (property "Footprint" "" (at 66.04 48.26 0)
      (effects (font (size 1.27 1.27)) hide)
    )
    (property "Datasheet" "" (at 66.04 48.26 0)
      (effects (font (size 1.27 1.27)) hide)
    )
    (pin "1")
    (instances
      (project "thunderbolt-pcie-adapter"
        (path ""
          (reference "#FLG05") (unit 1)
        )
      )
    )
  )

  (symbol (lib_id "antmicroResistors0402:R_10k_0402") (at 66.04 83.82 0) (unit 1)
    (in_bom yes) (on_board yes) (dnp no)
    (property "Reference" "R16" (at 64.77 82.55 0)
      (effects (font (size 1.27 1.27) (thickness 0.15)))
    )
    (property "Value" "R_10k_0402" (at 86.36 96.52 0)
      (effects (font (size 1.27 1.27) (thickness 0.15)) (justify left bottom) hide)
    )
    (property "Footprint" "antmicro-footprints:R_0402_1005Metric" (at 86.36 99.06 0)
      (effects (font (size 1.27 1.27) (thickness 0.15)) (justify left bottom) hide)
    )
    (property "Datasheet" "https://www.bourns.com/docs/product-datasheets/cr.pdf" (at 86.36 101.6 0)
      (effects (font (size 1.27 1.27) (thickness 0.15)) (justify left bottom) hide)
    )
    (property "MPN" "CR0402-FX-1002GLF" (at 86.36 104.14 0)
      (effects (font (size 1.27 1.27) (thickness 0.15)) (justify left bottom) hide)
    )
    (property "Manufacturer" "Bourns" (at 86.36 106.68 0)
      (effects (font (size 1.27 1.27) (thickness 0.15)) (justify left bottom) hide)
    )
    (property "License" "Apache-2.0" (at 86.36 109.22 0)
      (effects (font (size 1.27 1.27) (thickness 0.15)) (justify left bottom) hide)
    )
    (property "Val" "10k" (at 71.12 83.185 0)
      (effects (font (size 1.27 1.27) (thickness 0.15)) (justify left bottom))
    )
    (property "Tolerance" "1%" (at 86.36 93.98 0)
      (effects (font (size 1.27 1.27)) (justify left bottom) hide)
    )
    (property "Author" "Antmicro" (at 86.36 111.76 0)
      (effects (font (size 1.27 1.27) (thickness 0.15)) (justify left bottom) hide)
    )
    (pin "1")
    (pin "2")
    (instances
      (project "thunderbolt-pcie-adapter"
        (path ""
          (reference "R16") (unit 1)
        )
      )
    )
  )

  (symbol (lib_id "antmicroCapacitors0402:C_4n7_0402") (at 180.34 265.43 90) (unit 1)
    (in_bom yes) (on_board yes) (dnp no) (fields_autoplaced)
    (property "Reference" "C30" (at 182.88 261.6136 90)
      (effects (font (size 1.27 1.27) (thickness 0.15)) (justify right))
    )
    (property "Value" "C_4n7_0402" (at 190.5 245.11 0)
      (effects (font (size 1.27 1.27) (thickness 0.15)) (justify left bottom) hide)
    )
    (property "Footprint" "antmicro-footprints:C_0402_1005Metric" (at 193.04 245.11 0)
      (effects (font (size 1.27 1.27) (thickness 0.15)) (justify left bottom) hide)
    )
    (property "Datasheet" "https://product.tdk.com/en/search/capacitor/ceramic/mlcc/info?part_no=CGA2B3X7S2A472K050BB" (at 195.58 245.11 0)
      (effects (font (size 1.27 1.27) (thickness 0.15)) (justify left bottom) hide)
    )
    (property "MPN" "CGA2B3X7S2A472K050BB" (at 198.12 245.11 0)
      (effects (font (size 1.27 1.27) (thickness 0.15)) (justify left bottom) hide)
    )
    (property "Manufacturer" "TDK" (at 200.66 245.11 0)
      (effects (font (size 1.27 1.27) (thickness 0.15)) (justify left bottom) hide)
    )
    (property "License" "Apache-2.0" (at 203.2 245.11 0)
      (effects (font (size 1.27 1.27) (thickness 0.15)) (justify left bottom) hide)
    )
    (property "Val" "4n7" (at 182.88 264.1536 90)
      (effects (font (size 1.27 1.27) (thickness 0.15)) (justify right))
    )
    (property "Voltage" "" (at 208.28 245.11 0)
      (effects (font (size 1.27 1.27)) (justify left bottom) hide)
    )
    (property "Dielectric" "" (at 210.82 245.11 0)
      (effects (font (size 1.27 1.27)) (justify left bottom) hide)
    )
    (property "Author" "Antmicro" (at 205.74 245.11 0)
      (effects (font (size 1.27 1.27) (thickness 0.15)) (justify left bottom) hide)
    )
    (pin "1")
    (pin "2")
    (instances
      (project "thunderbolt-pcie-adapter"
        (path ""
          (reference "C30") (unit 1)
        )
      )
    )
  )

  (symbol (lib_id "antmicroResistors0402:R_3k3_0402") (at 66.04 81.28 0) (unit 1)
    (in_bom yes) (on_board yes) (dnp no)
    (property "Reference" "R15" (at 64.77 80.01 0)
      (effects (font (size 1.27 1.27) (thickness 0.15)))
    )
    (property "Value" "R_3k3_0402" (at 86.36 93.98 0)
      (effects (font (size 1.27 1.27) (thickness 0.15)) (justify left bottom) hide)
    )
    (property "Footprint" "antmicro-footprints:R_0402_1005Metric" (at 86.36 96.52 0)
      (effects (font (size 1.27 1.27) (thickness 0.15)) (justify left bottom) hide)
    )
    (property "Datasheet" "https://www.bourns.com/docs/product-datasheets/cr.pdf" (at 86.36 99.06 0)
      (effects (font (size 1.27 1.27) (thickness 0.15)) (justify left bottom) hide)
    )
    (property "MPN" "CR0402-FX-3301GLF" (at 86.36 101.6 0)
      (effects (font (size 1.27 1.27) (thickness 0.15)) (justify left bottom) hide)
    )
    (property "Manufacturer" "Bourns" (at 86.36 104.14 0)
      (effects (font (size 1.27 1.27) (thickness 0.15)) (justify left bottom) hide)
    )
    (property "License" "Apache-2.0" (at 86.36 106.68 0)
      (effects (font (size 1.27 1.27) (thickness 0.15)) (justify left bottom) hide)
    )
    (property "Val" "3k3" (at 71.12 80.645 0)
      (effects (font (size 1.27 1.27) (thickness 0.15)) (justify left bottom))
    )
    (property "Tolerance" "1%" (at 86.36 91.44 0)
      (effects (font (size 1.27 1.27)) (justify left bottom) hide)
    )
    (property "Author" "Antmicro" (at 86.36 109.22 0)
      (effects (font (size 1.27 1.27) (thickness 0.15)) (justify left bottom) hide)
    )
    (pin "1")
    (pin "2")
    (instances
      (project "thunderbolt-pcie-adapter"
        (path ""
          (reference "R15") (unit 1)
        )
      )
    )
  )

  (symbol (lib_id "antmicroResistors0402:R_0R_0402") (at 127 245.11 0) (unit 1)
    (in_bom yes) (on_board yes) (dnp no)
    (property "Reference" "R12" (at 125.73 243.84 0)
      (effects (font (size 1.27 1.27) (thickness 0.15)))
    )
    (property "Value" "R_0R_0402" (at 147.32 257.81 0)
      (effects (font (size 1.27 1.27) (thickness 0.15)) (justify left bottom) hide)
    )
    (property "Footprint" "antmicro-footprints:R_0402_1005Metric" (at 147.32 260.35 0)
      (effects (font (size 1.27 1.27) (thickness 0.15)) (justify left bottom) hide)
    )
    (property "Datasheet" "https://industrial.panasonic.com/cdbs/www-data/pdf/RDA0000/AOA0000C301.pdf" (at 147.32 262.89 0)
      (effects (font (size 1.27 1.27) (thickness 0.15)) (justify left bottom) hide)
    )
    (property "MPN" "ERJ2GE0R00X" (at 147.32 265.43 0)
      (effects (font (size 1.27 1.27) (thickness 0.15)) (justify left bottom) hide)
    )
    (property "Manufacturer" "Panasonic" (at 147.32 267.97 0)
      (effects (font (size 1.27 1.27) (thickness 0.15)) (justify left bottom) hide)
    )
    (property "License" "Apache-2.0" (at 147.32 270.51 0)
      (effects (font (size 1.27 1.27) (thickness 0.15)) (justify left bottom) hide)
    )
    (property "Val" "0R" (at 132.08 244.475 0)
      (effects (font (size 1.27 1.27) (thickness 0.15)) (justify left bottom))
    )
    (property "Tolerance" "~" (at 147.32 255.27 0)
      (effects (font (size 1.27 1.27)) (justify left bottom) hide)
    )
    (property "Current" "1A" (at 147.32 275.59 0)
      (effects (font (size 1.27 1.27) (thickness 0.15)) (justify left bottom) hide)
    )
    (property "Author" "Antmicro" (at 147.32 273.05 0)
      (effects (font (size 1.27 1.27) (thickness 0.15)) (justify left bottom) hide)
    )
    (pin "1")
    (pin "2")
    (instances
      (project "thunderbolt-pcie-adapter"
        (path ""
          (reference "R12") (unit 1)
        )
      )
    )
  )

  (symbol (lib_id "antmicroResistors0402:R_2k2_0402") (at 35.56 64.77 90) (unit 1)
    (in_bom yes) (on_board yes) (dnp no)
    (property "Reference" "R3" (at 36.83 60.96 90)
      (effects (font (size 1.27 1.27) (thickness 0.15)) (justify right))
    )
    (property "Value" "R_2k2_0402" (at 48.26 44.45 0)
      (effects (font (size 1.27 1.27) (thickness 0.15)) (justify left bottom) hide)
    )
    (property "Footprint" "antmicro-footprints:R_0402_1005Metric" (at 50.8 44.45 0)
      (effects (font (size 1.27 1.27) (thickness 0.15)) (justify left bottom) hide)
    )
    (property "Datasheet" "https://www.bourns.com/docs/product-datasheets/cr.pdf" (at 53.34 44.45 0)
      (effects (font (size 1.27 1.27) (thickness 0.15)) (justify left bottom) hide)
    )
    (property "MPN" "CR0402-FX-2201GLF" (at 55.88 44.45 0)
      (effects (font (size 1.27 1.27) (thickness 0.15)) (justify left bottom) hide)
    )
    (property "Manufacturer" "Bourns" (at 58.42 44.45 0)
      (effects (font (size 1.27 1.27) (thickness 0.15)) (justify left bottom) hide)
    )
    (property "License" "Apache-2.0" (at 60.96 44.45 0)
      (effects (font (size 1.27 1.27) (thickness 0.15)) (justify left bottom) hide)
    )
    (property "Val" "2k2" (at 40.005 62.23 90)
      (effects (font (size 1.27 1.27) (thickness 0.15)) (justify left bottom))
    )
    (property "Tolerance" "1%" (at 45.72 44.45 0)
      (effects (font (size 1.27 1.27)) (justify left bottom) hide)
    )
    (property "Author" "Antmicro" (at 63.5 44.45 0)
      (effects (font (size 1.27 1.27) (thickness 0.15)) (justify left bottom) hide)
    )
    (pin "1")
    (pin "2")
    (instances
      (project "thunderbolt-pcie-adapter"
        (path ""
          (reference "R3") (unit 1)
        )
      )
    )
  )

  (symbol (lib_id "antmicropower:GND") (at 135.89 109.22 90) (unit 1)
    (in_bom yes) (on_board yes) (dnp no)
    (property "Reference" "#PWR039" (at 142.24 109.22 0)
      (effects (font (size 1.27 1.27)) hide)
    )
    (property "Value" "GND" (at 140.335 111.125 0)
      (effects (font (size 1.27 1.27) (thickness 0.15)) (justify left bottom))
    )
    (property "Footprint" "" (at 135.89 109.22 0)
      (effects (font (size 1.27 1.27) (thickness 0.15)) (justify left bottom) hide)
    )
    (property "Datasheet" "" (at 135.89 109.22 0)
      (effects (font (size 1.27 1.27) (thickness 0.15)) (justify left bottom) hide)
    )
    (property "Author" "Antmicro" (at 143.51 100.33 0)
      (effects (font (size 1.27 1.27) (thickness 0.15)) (justify left bottom) hide)
    )
    (property "License" "Apache-2.0" (at 146.05 100.33 0)
      (effects (font (size 1.27 1.27) (thickness 0.15)) (justify left bottom) hide)
    )
    (pin "1")
    (instances
      (project "thunderbolt-pcie-adapter"
        (path ""
          (reference "#PWR039") (unit 1)
        )
      )
    )
  )

  (symbol (lib_id "antmicroResistors0402:R_100k_0402") (at 45.72 106.68 90) (unit 1)
    (in_bom yes) (on_board yes) (dnp no)
    (property "Reference" "R4" (at 46.99 102.87 90)
      (effects (font (size 1.27 1.27) (thickness 0.15)) (justify right))
    )
    (property "Value" "R_100k_0402" (at 58.42 86.36 0)
      (effects (font (size 1.27 1.27) (thickness 0.15)) (justify left bottom) hide)
    )
    (property "Footprint" "antmicro-footprints:R_0402_1005Metric" (at 60.96 86.36 0)
      (effects (font (size 1.27 1.27) (thickness 0.15)) (justify left bottom) hide)
    )
    (property "Datasheet" "https://www.bourns.com/docs/product-datasheets/cr.pdf" (at 63.5 86.36 0)
      (effects (font (size 1.27 1.27) (thickness 0.15)) (justify left bottom) hide)
    )
    (property "MPN" "CR0402-FX-1003GLF" (at 66.04 86.36 0)
      (effects (font (size 1.27 1.27) (thickness 0.15)) (justify left bottom) hide)
    )
    (property "Manufacturer" "Bourns" (at 68.58 86.36 0)
      (effects (font (size 1.27 1.27) (thickness 0.15)) (justify left bottom) hide)
    )
    (property "License" "Apache-2.0" (at 71.12 86.36 0)
      (effects (font (size 1.27 1.27) (thickness 0.15)) (justify left bottom) hide)
    )
    (property "Val" "100k" (at 52.07 104.14 90)
      (effects (font (size 1.27 1.27) (thickness 0.15)) (justify left bottom))
    )
    (property "Tolerance" "1%" (at 55.88 86.36 0)
      (effects (font (size 1.27 1.27)) (justify left bottom) hide)
    )
    (property "Author" "Antmicro" (at 73.66 86.36 0)
      (effects (font (size 1.27 1.27) (thickness 0.15)) (justify left bottom) hide)
    )
    (pin "1")
    (pin "2")
    (instances
      (project "thunderbolt-pcie-adapter"
        (path ""
          (reference "R4") (unit 1)
        )
      )
    )
  )

  (symbol (lib_id "antmicropower:PWR_FLAG") (at 292.1 146.05 0) (unit 1)
    (in_bom yes) (on_board yes) (dnp no)
    (property "Reference" "#FLG0112" (at 292.1 144.145 0)
      (effects (font (size 1.27 1.27)) hide)
    )
    (property "Value" "PWR_FLAG" (at 292.1 142.24 0)
      (effects (font (size 1.27 1.27)))
    )
    (property "Footprint" "" (at 292.1 146.05 0)
      (effects (font (size 1.27 1.27)) hide)
    )
    (property "Datasheet" "" (at 292.1 146.05 0)
      (effects (font (size 1.27 1.27)) hide)
    )
    (pin "1")
    (instances
      (project "thunderbolt-pcie-adapter"
        (path ""
          (reference "#FLG0112") (unit 1)
        )
      )
    )
  )

  (symbol (lib_id "antmicroCapacitors0603:C_22u_16V_0603") (at 210.82 219.71 90) (unit 1)
    (in_bom yes) (on_board yes) (dnp no) (fields_autoplaced)
    (property "Reference" "C40" (at 213.36 215.8936 90)
      (effects (font (size 1.27 1.27) (thickness 0.15)) (justify right))
    )
    (property "Value" "C_22u_16V_0603" (at 220.98 199.39 0)
      (effects (font (size 1.27 1.27) (thickness 0.15)) (justify left bottom) hide)
    )
    (property "Footprint" "antmicro-footprints:C_0603_1608Metric" (at 223.52 199.39 0)
      (effects (font (size 1.27 1.27) (thickness 0.15)) (justify left bottom) hide)
    )
    (property "Datasheet" "https://product.samsungsem.com/mlcc/CL10A226MO7JZN.do" (at 226.06 199.39 0)
      (effects (font (size 1.27 1.27) (thickness 0.15)) (justify left bottom) hide)
    )
    (property "MPN" "CL10A226MO7JZNC" (at 228.6 199.39 0)
      (effects (font (size 1.27 1.27) (thickness 0.15)) (justify left bottom) hide)
    )
    (property "Manufacturer" "Samsung Electro-Mechanics" (at 231.14 199.39 0)
      (effects (font (size 1.27 1.27) (thickness 0.15)) (justify left bottom) hide)
    )
    (property "License" "Apache-2.0" (at 233.68 199.39 0)
      (effects (font (size 1.27 1.27) (thickness 0.15)) (justify left bottom) hide)
    )
    (property "Val" "22u" (at 213.36 218.4336 90)
      (effects (font (size 1.27 1.27) (thickness 0.15)) (justify right))
    )
    (property "Voltage" "16V" (at 238.76 199.39 0)
      (effects (font (size 1.27 1.27)) (justify left bottom) hide)
    )
    (property "Dielectric" "" (at 241.3 199.39 0)
      (effects (font (size 1.27 1.27)) (justify left bottom) hide)
    )
    (property "Author" "Antmicro" (at 236.22 199.39 0)
      (effects (font (size 1.27 1.27) (thickness 0.15)) (justify left bottom) hide)
    )
    (pin "1")
    (pin "2")
    (instances
      (project "thunderbolt-pcie-adapter"
        (path ""
          (reference "C40") (unit 1)
        )
      )
    )
  )

  (symbol (lib_id "antmicroCapacitorsmisc:C_22u_1206_35V") (at 262.89 50.8 90) (unit 1)
    (in_bom yes) (on_board yes) (dnp no)
    (property "Reference" "C15" (at 263.525 46.355 90)
      (effects (font (size 1.27 1.27) (thickness 0.15)) (justify right))
    )
    (property "Value" "C_22u_1206_35V" (at 273.05 30.48 0)
      (effects (font (size 1.27 1.27) (thickness 0.15)) (justify left bottom) hide)
    )
    (property "Footprint" "antmicro-footprints:C_1206_3216Metric" (at 275.59 30.48 0)
      (effects (font (size 1.27 1.27) (thickness 0.15)) (justify left bottom) hide)
    )
    (property "Datasheet" "https://product.tdk.com/en/search/capacitor/ceramic/mlcc/info?part_no=3216X5R1V226M160AC" (at 278.13 30.48 0)
      (effects (font (size 1.27 1.27) (thickness 0.15)) (justify left bottom) hide)
    )
    (property "MPN" "3216X5R1V226M160AC" (at 280.67 30.48 0)
      (effects (font (size 1.27 1.27) (thickness 0.15)) (justify left bottom) hide)
    )
    (property "Manufacturer" "TDK" (at 283.21 30.48 0)
      (effects (font (size 1.27 1.27) (thickness 0.15)) (justify left bottom) hide)
    )
    (property "License" "Apache-2.0" (at 285.75 30.48 0)
      (effects (font (size 1.27 1.27) (thickness 0.15)) (justify left bottom) hide)
    )
    (property "Val" "22u" (at 267.335 50.165 90)
      (effects (font (size 1.27 1.27) (thickness 0.15)) (justify left bottom))
    )
    (property "Voltage" "35V" (at 290.83 30.48 0)
      (effects (font (size 1.27 1.27)) (justify left bottom) hide)
    )
    (property "Dielectric" "" (at 293.37 30.48 0)
      (effects (font (size 1.27 1.27)) (justify left bottom) hide)
    )
    (property "Author" "Antmicro" (at 288.29 30.48 0)
      (effects (font (size 1.27 1.27) (thickness 0.15)) (justify left bottom) hide)
    )
    (pin "1")
    (pin "2")
    (instances
      (project "thunderbolt-pcie-adapter"
        (path ""
          (reference "C15") (unit 1)
        )
      )
    )
  )

  (symbol (lib_id "antmicroTestPoints:TP_1mm_SMD") (at 49.53 257.81 90) (unit 1)
    (in_bom no) (on_board yes) (dnp no)
    (property "Reference" "TP12" (at 47.625 252.73 90)
      (effects (font (size 1.27 1.27) (thickness 0.15)) (justify right))
    )
    (property "Value" "TP_1mm_SMD" (at 57.15 242.57 0)
      (effects (font (size 1.27 1.27) (thickness 0.15)) (justify left bottom) hide)
    )
    (property "Footprint" "antmicro-footprints:TP_SMD_1mm" (at 59.69 242.57 0)
      (effects (font (size 1.27 1.27) (thickness 0.15)) (justify left bottom) hide)
    )
    (property "Datasheet" "" (at 62.23 240.03 0)
      (effects (font (size 1.27 1.27) (thickness 0.15)) (justify left bottom) hide)
    )
    (property "License" "Apache-2.0" (at 67.31 242.57 0)
      (effects (font (size 1.27 1.27) (thickness 0.15)) (justify left bottom) hide)
    )
    (property "Manufacturer" "" (at 49.53 257.81 0)
      (effects (font (size 1.27 1.27)) hide)
    )
    (property "MPN" "" (at 49.53 257.81 0)
      (effects (font (size 1.27 1.27)) hide)
    )
    (property "Author" "Antmicro" (at 64.77 242.57 0)
      (effects (font (size 1.27 1.27) (thickness 0.15)) (justify left bottom) hide)
    )
    (pin "1")
    (instances
      (project "thunderbolt-pcie-adapter"
        (path ""
          (reference "TP12") (unit 1)
        )
      )
    )
  )

  (symbol (lib_id "antmicroLEDIndicationDiscrete:LED_G_0603_KP-1608CGCK") (at 251.46 162.56 90) (unit 1)
    (in_bom yes) (on_board yes) (dnp no)
    (property "Reference" "D5" (at 248.285 161.29 90)
      (effects (font (size 1.27 1.27) (thickness 0.15)) (justify left))
    )
    (property "Value" "LED_G_0603_KP-1608CGCK" (at 259.08 139.7 0)
      (effects (font (size 1.27 1.27) (thickness 0.15)) (justify left bottom) hide)
    )
    (property "Footprint" "antmicro-footprints:LED_0603_1608Metric_G" (at 261.62 139.7 0)
      (effects (font (size 1.27 1.27) (thickness 0.15)) (justify left bottom) hide)
    )
    (property "Datasheet" "http://www.kingbright.com/attachments/file/psearch//000/00/00/KP-1608CGCK(Ver.23B).pdf" (at 264.16 139.7 0)
      (effects (font (size 1.27 1.27) (thickness 0.15)) (justify left bottom) hide)
    )
    (property "MPN" "KP-1608CGCK" (at 266.7 139.7 0)
      (effects (font (size 1.27 1.27) (thickness 0.15)) (justify left bottom) hide)
    )
    (property "Manufacturer" "Kingbright" (at 269.24 139.7 0)
      (effects (font (size 1.27 1.27) (thickness 0.15)) (justify left bottom) hide)
    )
    (property "License" "Apache-2.0" (at 274.32 139.7 0)
      (effects (font (size 1.27 1.27) (thickness 0.15)) (justify left bottom) hide)
    )
    (property "Author" "Antmicro" (at 271.78 139.7 0)
      (effects (font (size 1.27 1.27) (thickness 0.15)) (justify left bottom) hide)
    )
    (property "Color" "Green" (at 250.825 162.56 90)
      (effects (font (size 1.27 1.27)) (justify left bottom))
    )
    (pin "1")
    (pin "2")
    (instances
      (project "thunderbolt-pcie-adapter"
        (path ""
          (reference "D5") (unit 1)
        )
      )
    )
  )

  (symbol (lib_id "antmicroFerriteBeadsandChips:FB_30Z_8.5A_Murata-BLM21SN_0805") (at 229.87 43.18 0) (mirror x) (unit 1)
    (in_bom yes) (on_board yes) (dnp no)
    (property "Reference" "FB2" (at 232.41 40.005 0)
      (effects (font (size 1.27 1.27) (thickness 0.15)))
    )
    (property "Value" "FB_30Z_8.5A_Murata-BLM21SN_0805" (at 243.84 40.64 0)
      (effects (font (size 1.27 1.27) (thickness 0.15)) (justify left bottom) hide)
    )
    (property "Footprint" "antmicro-footprints:FB_0805_2012Metric" (at 243.84 35.56 0)
      (effects (font (size 1.27 1.27) (thickness 0.15)) (justify left bottom) hide)
    )
    (property "Datasheet" "https://www.murata.com/en-sg/products/productdata/8796738977822/ENFA0005.pdf?1519270210000" (at 243.84 33.02 0)
      (effects (font (size 1.27 1.27) (thickness 0.15)) (justify left bottom) hide)
    )
    (property "MPN" "BLM21SN300SZ1D" (at 243.84 30.48 0)
      (effects (font (size 1.27 1.27) (thickness 0.15)) (justify left bottom) hide)
    )
    (property "Manufacturer" "Murata" (at 243.84 27.94 0)
      (effects (font (size 1.27 1.27) (thickness 0.15)) (justify left bottom) hide)
    )
    (property "License" "Apache-2.0" (at 243.84 22.86 0)
      (effects (font (size 1.27 1.27) (thickness 0.15)) (justify left bottom) hide)
    )
    (property "Author" "Antmicro" (at 243.84 25.4 0)
      (effects (font (size 1.27 1.27) (thickness 0.15)) (justify left bottom) hide)
    )
    (property "Val" "30Z/8.5A" (at 227.965 45.72 0)
      (effects (font (size 1.27 1.27)) (justify left bottom))
    )
    (property "Current" "" (at 250.19 20.32 0)
      (effects (font (size 1.27 1.27) (thickness 0.15)) (justify left bottom) hide)
    )
    (pin "1")
    (pin "2")
    (instances
      (project "thunderbolt-pcie-adapter"
        (path ""
          (reference "FB2") (unit 1)
        )
      )
    )
  )

  (symbol (lib_id "antmicroCapacitors0603:C_22u_0603") (at 358.14 71.12 90) (unit 1)
    (in_bom yes) (on_board yes) (dnp no)
    (property "Reference" "C44" (at 358.775 66.675 90)
      (effects (font (size 1.27 1.27) (thickness 0.15)) (justify right))
    )
    (property "Value" "C_22u_0603" (at 368.3 50.8 0)
      (effects (font (size 1.27 1.27) (thickness 0.15)) (justify left bottom) hide)
    )
    (property "Footprint" "antmicro-footprints:C_0603_1608Metric" (at 370.84 50.8 0)
      (effects (font (size 1.27 1.27) (thickness 0.15)) (justify left bottom) hide)
    )
    (property "Datasheet" "https://www.murata.com/products/productdetail?partno=GRM188R60J226MEA0%23" (at 373.38 50.8 0)
      (effects (font (size 1.27 1.27) (thickness 0.15)) (justify left bottom) hide)
    )
    (property "MPN" "GRM188R60J226MEA0D" (at 375.92 50.8 0)
      (effects (font (size 1.27 1.27) (thickness 0.15)) (justify left bottom) hide)
    )
    (property "Manufacturer" "Murata" (at 378.46 50.8 0)
      (effects (font (size 1.27 1.27) (thickness 0.15)) (justify left bottom) hide)
    )
    (property "License" "Apache-2.0" (at 381 50.8 0)
      (effects (font (size 1.27 1.27) (thickness 0.15)) (justify left bottom) hide)
    )
    (property "Val" "22u" (at 363.22 69.215 90)
      (effects (font (size 1.27 1.27) (thickness 0.15)) (justify left bottom))
    )
    (property "Voltage" "" (at 386.08 50.8 0)
      (effects (font (size 1.27 1.27)) (justify left bottom) hide)
    )
    (property "Dielectric" "" (at 388.62 50.8 0)
      (effects (font (size 1.27 1.27)) (justify left bottom) hide)
    )
    (property "Author" "Antmicro" (at 383.54 50.8 0)
      (effects (font (size 1.27 1.27) (thickness 0.15)) (justify left bottom) hide)
    )
    (pin "1")
    (pin "2")
    (instances
      (project "thunderbolt-pcie-adapter"
        (path ""
          (reference "C44") (unit 1)
        )
      )
    )
  )

  (symbol (lib_id "antmicropower:GND") (at 49.53 267.97 0) (unit 1)
    (in_bom yes) (on_board yes) (dnp no)
    (property "Reference" "#PWR0165" (at 49.53 274.32 0)
      (effects (font (size 1.27 1.27)) hide)
    )
    (property "Value" "GND" (at 47.625 272.415 0)
      (effects (font (size 1.27 1.27) (thickness 0.15)) (justify left bottom))
    )
    (property "Footprint" "" (at 49.53 267.97 0)
      (effects (font (size 1.27 1.27) (thickness 0.15)) (justify left bottom) hide)
    )
    (property "Datasheet" "" (at 49.53 267.97 0)
      (effects (font (size 1.27 1.27) (thickness 0.15)) (justify left bottom) hide)
    )
    (property "Author" "Antmicro" (at 58.42 275.59 0)
      (effects (font (size 1.27 1.27) (thickness 0.15)) (justify left bottom) hide)
    )
    (property "License" "Apache-2.0" (at 58.42 278.13 0)
      (effects (font (size 1.27 1.27) (thickness 0.15)) (justify left bottom) hide)
    )
    (pin "1")
    (instances
      (project "thunderbolt-pcie-adapter"
        (path ""
          (reference "#PWR0165") (unit 1)
        )
      )
    )
  )

  (symbol (lib_id "antmicroTestPoints:TP_1mm_SMD") (at 224.79 41.91 90) (unit 1)
    (in_bom no) (on_board yes) (dnp no)
    (property "Reference" "TP1" (at 222.885 36.83 90)
      (effects (font (size 1.27 1.27) (thickness 0.15)) (justify right))
    )
    (property "Value" "TP_1mm_SMD" (at 232.41 26.67 0)
      (effects (font (size 1.27 1.27) (thickness 0.15)) (justify left bottom) hide)
    )
    (property "Footprint" "antmicro-footprints:TP_SMD_1mm" (at 234.95 26.67 0)
      (effects (font (size 1.27 1.27) (thickness 0.15)) (justify left bottom) hide)
    )
    (property "Datasheet" "" (at 237.49 24.13 0)
      (effects (font (size 1.27 1.27) (thickness 0.15)) (justify left bottom) hide)
    )
    (property "License" "Apache-2.0" (at 242.57 26.67 0)
      (effects (font (size 1.27 1.27) (thickness 0.15)) (justify left bottom) hide)
    )
    (property "Manufacturer" "" (at 224.79 41.91 0)
      (effects (font (size 1.27 1.27)) hide)
    )
    (property "MPN" "" (at 224.79 41.91 0)
      (effects (font (size 1.27 1.27)) hide)
    )
    (property "Author" "Antmicro" (at 240.03 26.67 0)
      (effects (font (size 1.27 1.27) (thickness 0.15)) (justify left bottom) hide)
    )
    (pin "1")
    (instances
      (project "thunderbolt-pcie-adapter"
        (path ""
          (reference "TP1") (unit 1)
        )
      )
    )
  )

  (symbol (lib_id "antmicropower:GND") (at 165.1 266.7 0) (unit 1)
    (in_bom yes) (on_board yes) (dnp no)
    (property "Reference" "#PWR0175" (at 165.1 273.05 0)
      (effects (font (size 1.27 1.27)) hide)
    )
    (property "Value" "GND" (at 163.195 271.145 0)
      (effects (font (size 1.27 1.27) (thickness 0.15)) (justify left bottom))
    )
    (property "Footprint" "" (at 165.1 266.7 0)
      (effects (font (size 1.27 1.27) (thickness 0.15)) (justify left bottom) hide)
    )
    (property "Datasheet" "" (at 165.1 266.7 0)
      (effects (font (size 1.27 1.27) (thickness 0.15)) (justify left bottom) hide)
    )
    (property "Author" "Antmicro" (at 173.99 274.32 0)
      (effects (font (size 1.27 1.27) (thickness 0.15)) (justify left bottom) hide)
    )
    (property "License" "Apache-2.0" (at 173.99 276.86 0)
      (effects (font (size 1.27 1.27) (thickness 0.15)) (justify left bottom) hide)
    )
    (pin "1")
    (instances
      (project "thunderbolt-pcie-adapter"
        (path ""
          (reference "#PWR0175") (unit 1)
        )
      )
    )
  )

  (symbol (lib_id "antmicropower:GND") (at 278.13 171.45 0) (unit 1)
    (in_bom yes) (on_board yes) (dnp no)
    (property "Reference" "#PWR0156" (at 278.13 177.8 0)
      (effects (font (size 1.27 1.27)) hide)
    )
    (property "Value" "GND" (at 276.225 175.895 0)
      (effects (font (size 1.27 1.27) (thickness 0.15)) (justify left bottom))
    )
    (property "Footprint" "" (at 278.13 171.45 0)
      (effects (font (size 1.27 1.27) (thickness 0.15)) (justify left bottom) hide)
    )
    (property "Datasheet" "" (at 278.13 171.45 0)
      (effects (font (size 1.27 1.27) (thickness 0.15)) (justify left bottom) hide)
    )
    (property "Author" "Antmicro" (at 287.02 179.07 0)
      (effects (font (size 1.27 1.27) (thickness 0.15)) (justify left bottom) hide)
    )
    (property "License" "Apache-2.0" (at 287.02 181.61 0)
      (effects (font (size 1.27 1.27) (thickness 0.15)) (justify left bottom) hide)
    )
    (pin "1")
    (instances
      (project "thunderbolt-pcie-adapter"
        (path ""
          (reference "#PWR0156") (unit 1)
        )
      )
    )
  )

  (symbol (lib_id "antmicropower:GND") (at 224.79 53.34 0) (unit 1)
    (in_bom yes) (on_board yes) (dnp no)
    (property "Reference" "#PWR015" (at 224.79 59.69 0)
      (effects (font (size 1.27 1.27)) hide)
    )
    (property "Value" "GND" (at 222.885 57.785 0)
      (effects (font (size 1.27 1.27) (thickness 0.15)) (justify left bottom))
    )
    (property "Footprint" "" (at 224.79 53.34 0)
      (effects (font (size 1.27 1.27) (thickness 0.15)) (justify left bottom) hide)
    )
    (property "Datasheet" "" (at 224.79 53.34 0)
      (effects (font (size 1.27 1.27) (thickness 0.15)) (justify left bottom) hide)
    )
    (property "Author" "Antmicro" (at 233.68 60.96 0)
      (effects (font (size 1.27 1.27) (thickness 0.15)) (justify left bottom) hide)
    )
    (property "License" "Apache-2.0" (at 233.68 63.5 0)
      (effects (font (size 1.27 1.27) (thickness 0.15)) (justify left bottom) hide)
    )
    (pin "1")
    (instances
      (project "thunderbolt-pcie-adapter"
        (path ""
          (reference "#PWR015") (unit 1)
        )
      )
    )
  )

  (symbol (lib_id "antmicropower:GND") (at 180.34 266.7 0) (unit 1)
    (in_bom yes) (on_board yes) (dnp no)
    (property "Reference" "#PWR0178" (at 180.34 273.05 0)
      (effects (font (size 1.27 1.27)) hide)
    )
    (property "Value" "GND" (at 178.435 271.145 0)
      (effects (font (size 1.27 1.27) (thickness 0.15)) (justify left bottom))
    )
    (property "Footprint" "" (at 180.34 266.7 0)
      (effects (font (size 1.27 1.27) (thickness 0.15)) (justify left bottom) hide)
    )
    (property "Datasheet" "" (at 180.34 266.7 0)
      (effects (font (size 1.27 1.27) (thickness 0.15)) (justify left bottom) hide)
    )
    (property "Author" "Antmicro" (at 189.23 274.32 0)
      (effects (font (size 1.27 1.27) (thickness 0.15)) (justify left bottom) hide)
    )
    (property "License" "Apache-2.0" (at 189.23 276.86 0)
      (effects (font (size 1.27 1.27) (thickness 0.15)) (justify left bottom) hide)
    )
    (pin "1")
    (instances
      (project "thunderbolt-pcie-adapter"
        (path ""
          (reference "#PWR0178") (unit 1)
        )
      )
    )
  )

  (symbol (lib_id "antmicroCapacitorsmisc:C_22u_1206_35V") (at 252.73 50.8 90) (unit 1)
    (in_bom yes) (on_board yes) (dnp no)
    (property "Reference" "C13" (at 253.365 46.355 90)
      (effects (font (size 1.27 1.27) (thickness 0.15)) (justify right))
    )
    (property "Value" "C_22u_1206_35V" (at 262.89 30.48 0)
      (effects (font (size 1.27 1.27) (thickness 0.15)) (justify left bottom) hide)
    )
    (property "Footprint" "antmicro-footprints:C_1206_3216Metric" (at 265.43 30.48 0)
      (effects (font (size 1.27 1.27) (thickness 0.15)) (justify left bottom) hide)
    )
    (property "Datasheet" "https://product.tdk.com/en/search/capacitor/ceramic/mlcc/info?part_no=3216X5R1V226M160AC" (at 267.97 30.48 0)
      (effects (font (size 1.27 1.27) (thickness 0.15)) (justify left bottom) hide)
    )
    (property "MPN" "3216X5R1V226M160AC" (at 270.51 30.48 0)
      (effects (font (size 1.27 1.27) (thickness 0.15)) (justify left bottom) hide)
    )
    (property "Manufacturer" "TDK" (at 273.05 30.48 0)
      (effects (font (size 1.27 1.27) (thickness 0.15)) (justify left bottom) hide)
    )
    (property "License" "Apache-2.0" (at 275.59 30.48 0)
      (effects (font (size 1.27 1.27) (thickness 0.15)) (justify left bottom) hide)
    )
    (property "Val" "22u" (at 257.175 50.165 90)
      (effects (font (size 1.27 1.27) (thickness 0.15)) (justify left bottom))
    )
    (property "Voltage" "35V" (at 280.67 30.48 0)
      (effects (font (size 1.27 1.27)) (justify left bottom) hide)
    )
    (property "Dielectric" "" (at 283.21 30.48 0)
      (effects (font (size 1.27 1.27)) (justify left bottom) hide)
    )
    (property "Author" "Antmicro" (at 278.13 30.48 0)
      (effects (font (size 1.27 1.27) (thickness 0.15)) (justify left bottom) hide)
    )
    (pin "1")
    (pin "2")
    (instances
      (project "thunderbolt-pcie-adapter"
        (path ""
          (reference "C13") (unit 1)
        )
      )
    )
  )

  (symbol (lib_id "antmicroResistors0402:R_2k2_0402") (at 331.47 170.18 90) (unit 1)
    (in_bom yes) (on_board yes) (dnp no) (fields_autoplaced)
    (property "Reference" "R46" (at 334.01 166.37 90)
      (effects (font (size 1.27 1.27) (thickness 0.15)) (justify right))
    )
    (property "Value" "R_2k2_0402" (at 344.17 149.86 0)
      (effects (font (size 1.27 1.27) (thickness 0.15)) (justify left bottom) hide)
    )
    (property "Footprint" "antmicro-footprints:R_0402_1005Metric" (at 346.71 149.86 0)
      (effects (font (size 1.27 1.27) (thickness 0.15)) (justify left bottom) hide)
    )
    (property "Datasheet" "https://www.bourns.com/docs/product-datasheets/cr.pdf" (at 349.25 149.86 0)
      (effects (font (size 1.27 1.27) (thickness 0.15)) (justify left bottom) hide)
    )
    (property "MPN" "CR0402-FX-2201GLF" (at 351.79 149.86 0)
      (effects (font (size 1.27 1.27) (thickness 0.15)) (justify left bottom) hide)
    )
    (property "Manufacturer" "Bourns" (at 354.33 149.86 0)
      (effects (font (size 1.27 1.27) (thickness 0.15)) (justify left bottom) hide)
    )
    (property "License" "Apache-2.0" (at 356.87 149.86 0)
      (effects (font (size 1.27 1.27) (thickness 0.15)) (justify left bottom) hide)
    )
    (property "Val" "2k2" (at 334.01 168.91 90)
      (effects (font (size 1.27 1.27) (thickness 0.15)) (justify right))
    )
    (property "Tolerance" "1%" (at 341.63 149.86 0)
      (effects (font (size 1.27 1.27)) (justify left bottom) hide)
    )
    (property "Author" "Antmicro" (at 359.41 149.86 0)
      (effects (font (size 1.27 1.27) (thickness 0.15)) (justify left bottom) hide)
    )
    (pin "1")
    (pin "2")
    (instances
      (project "thunderbolt-pcie-adapter"
        (path ""
          (reference "R46") (unit 1)
        )
      )
    )
  )

  (symbol (lib_id "antmicroResistors0402:R_3k3_0402") (at 66.04 78.74 0) (unit 1)
    (in_bom yes) (on_board yes) (dnp no)
    (property "Reference" "R14" (at 64.77 77.47 0)
      (effects (font (size 1.27 1.27) (thickness 0.15)))
    )
    (property "Value" "R_3k3_0402" (at 86.36 91.44 0)
      (effects (font (size 1.27 1.27) (thickness 0.15)) (justify left bottom) hide)
    )
    (property "Footprint" "antmicro-footprints:R_0402_1005Metric" (at 86.36 93.98 0)
      (effects (font (size 1.27 1.27) (thickness 0.15)) (justify left bottom) hide)
    )
    (property "Datasheet" "https://www.bourns.com/docs/product-datasheets/cr.pdf" (at 86.36 96.52 0)
      (effects (font (size 1.27 1.27) (thickness 0.15)) (justify left bottom) hide)
    )
    (property "MPN" "CR0402-FX-3301GLF" (at 86.36 99.06 0)
      (effects (font (size 1.27 1.27) (thickness 0.15)) (justify left bottom) hide)
    )
    (property "Manufacturer" "Bourns" (at 86.36 101.6 0)
      (effects (font (size 1.27 1.27) (thickness 0.15)) (justify left bottom) hide)
    )
    (property "License" "Apache-2.0" (at 86.36 104.14 0)
      (effects (font (size 1.27 1.27) (thickness 0.15)) (justify left bottom) hide)
    )
    (property "Val" "3k3" (at 71.12 78.105 0)
      (effects (font (size 1.27 1.27) (thickness 0.15)) (justify left bottom))
    )
    (property "Tolerance" "1%" (at 86.36 88.9 0)
      (effects (font (size 1.27 1.27)) (justify left bottom) hide)
    )
    (property "Author" "Antmicro" (at 86.36 106.68 0)
      (effects (font (size 1.27 1.27) (thickness 0.15)) (justify left bottom) hide)
    )
    (pin "1")
    (pin "2")
    (instances
      (project "thunderbolt-pcie-adapter"
        (path ""
          (reference "R14") (unit 1)
        )
      )
    )
  )

  (symbol (lib_id "antmicropower:GND") (at 36.83 215.9 0) (unit 1)
    (in_bom yes) (on_board yes) (dnp no)
    (property "Reference" "#PWR05" (at 36.83 222.25 0)
      (effects (font (size 1.27 1.27)) hide)
    )
    (property "Value" "GND" (at 34.925 220.345 0)
      (effects (font (size 1.27 1.27) (thickness 0.15)) (justify left bottom))
    )
    (property "Footprint" "" (at 36.83 215.9 0)
      (effects (font (size 1.27 1.27) (thickness 0.15)) (justify left bottom) hide)
    )
    (property "Datasheet" "" (at 36.83 215.9 0)
      (effects (font (size 1.27 1.27) (thickness 0.15)) (justify left bottom) hide)
    )
    (property "Author" "Antmicro" (at 45.72 223.52 0)
      (effects (font (size 1.27 1.27) (thickness 0.15)) (justify left bottom) hide)
    )
    (property "License" "Apache-2.0" (at 45.72 226.06 0)
      (effects (font (size 1.27 1.27) (thickness 0.15)) (justify left bottom) hide)
    )
    (pin "1")
    (instances
      (project "thunderbolt-pcie-adapter"
        (path ""
          (reference "#PWR05") (unit 1)
        )
      )
    )
  )

  (symbol (lib_id "antmicroFixedInductors:L_2u2_9.7A_Coilcraft-XAL5030") (at 318.77 59.69 0) (unit 1)
    (in_bom yes) (on_board yes) (dnp no)
    (property "Reference" "L2" (at 321.31 57.785 0)
      (effects (font (size 1.27 1.27) (thickness 0.15)))
    )
    (property "Value" "L_2u2_9.7A_Coilcraft-XAL5030" (at 332.74 62.23 0)
      (effects (font (size 1.27 1.27) (thickness 0.15)) (justify left bottom) hide)
    )
    (property "Footprint" "antmicro-footprints:L_Coilcraft-XAL5030" (at 332.74 67.31 0)
      (effects (font (size 1.27 1.27) (thickness 0.15)) (justify left bottom) hide)
    )
    (property "Datasheet" "https://www.coilcraft.com/getmedia/49bc46c8-4b2c-45b9-9b6c-2eaa235ea698/xal50xx.pdf" (at 332.74 69.85 0)
      (effects (font (size 1.27 1.27) (thickness 0.15)) (justify left bottom) hide)
    )
    (property "Val" "2u2/9.7A" (at 316.865 62.23 0)
      (effects (font (size 1.27 1.27) (thickness 0.15)) (justify left bottom))
    )
    (property "Manufacturer" "Coilcraft" (at 332.74 72.39 0)
      (effects (font (size 1.27 1.27) (thickness 0.15)) (justify left bottom) hide)
    )
    (property "MPN" "XAL5030-222MEC" (at 332.74 74.93 0)
      (effects (font (size 1.27 1.27) (thickness 0.15)) (justify left bottom) hide)
    )
    (property "ISat" "9.2 A" (at 332.74 76.2 0)
      (effects (font (size 1.27 1.27)) (justify left) hide)
    )
    (property "IMax" "9.7 A" (at 332.74 80.01 0)
      (effects (font (size 1.27 1.27) (thickness 0.15)) (justify left bottom) hide)
    )
    (property "Size" "5.28x5.48" (at 332.74 82.55 0)
      (effects (font (size 1.27 1.27) (thickness 0.15)) (justify left bottom) hide)
    )
    (property "License" "Apache-2.0" (at 332.74 87.63 0)
      (effects (font (size 1.27 1.27) (thickness 0.15)) (justify left bottom) hide)
    )
    (property "Author" "Antmicro" (at 332.74 85.09 0)
      (effects (font (size 1.27 1.27) (thickness 0.15)) (justify left bottom) hide)
    )
    (pin "1")
    (pin "2")
    (instances
      (project "thunderbolt-pcie-adapter"
        (path ""
          (reference "L2") (unit 1)
        )
      )
    )
  )

  (symbol (lib_id "antmicroCapacitors0402:C_1u_0402") (at 119.38 217.17 0) (mirror x) (unit 1)
    (in_bom yes) (on_board yes) (dnp no)
    (property "Reference" "C18" (at 119.38 215.9 0)
      (effects (font (size 1.27 1.27) (thickness 0.15)))
    )
    (property "Value" "C_1u_0402" (at 139.7 207.01 0)
      (effects (font (size 1.27 1.27) (thickness 0.15)) (justify left bottom) hide)
    )
    (property "Footprint" "antmicro-footprints:C_0402_1005Metric" (at 139.7 204.47 0)
      (effects (font (size 1.27 1.27) (thickness 0.15)) (justify left bottom) hide)
    )
    (property "Datasheet" "https://product.tdk.com/en/search/capacitor/ceramic/mlcc/info?part_no=C1005X6S1A105K050BC" (at 139.7 201.93 0)
      (effects (font (size 1.27 1.27) (thickness 0.15)) (justify left bottom) hide)
    )
    (property "MPN" "C1005X6S1A105K050BC" (at 139.7 199.39 0)
      (effects (font (size 1.27 1.27) (thickness 0.15)) (justify left bottom) hide)
    )
    (property "Manufacturer" "TDK" (at 139.7 196.85 0)
      (effects (font (size 1.27 1.27) (thickness 0.15)) (justify left bottom) hide)
    )
    (property "License" "Apache-2.0" (at 139.7 194.31 0)
      (effects (font (size 1.27 1.27) (thickness 0.15)) (justify left bottom) hide)
    )
    (property "Val" "1u" (at 124.46 215.9 0)
      (effects (font (size 1.27 1.27) (thickness 0.15)))
    )
    (property "Voltage" "" (at 139.7 189.23 0)
      (effects (font (size 1.27 1.27)) (justify left bottom) hide)
    )
    (property "Dielectric" "" (at 139.7 186.69 0)
      (effects (font (size 1.27 1.27)) (justify left bottom) hide)
    )
    (property "Author" "Antmicro" (at 139.7 191.77 0)
      (effects (font (size 1.27 1.27) (thickness 0.15)) (justify left bottom) hide)
    )
    (pin "1")
    (pin "2")
    (instances
      (project "thunderbolt-pcie-adapter"
        (path ""
          (reference "C18") (unit 1)
        )
      )
    )
  )

  (symbol (lib_id "antmicroResistorsmisc:R_0R02_1206") (at 250.19 212.09 0) (unit 1)
    (in_bom yes) (on_board yes) (dnp no) (fields_autoplaced)
    (property "Reference" "R45" (at 252.73 205.74 0)
      (effects (font (size 1.27 1.27) (thickness 0.15)))
    )
    (property "Value" "R_0R02_1206" (at 270.51 224.79 0)
      (effects (font (size 1.27 1.27) (thickness 0.15)) (justify left bottom) hide)
    )
    (property "Footprint" "antmicro-footprints:R_1206_3216Metric" (at 270.51 227.33 0)
      (effects (font (size 1.27 1.27) (thickness 0.15)) (justify left bottom) hide)
    )
    (property "Datasheet" "https://www.mouser.com/datasheet/2/427/wslp-1763037.pdf" (at 270.51 229.87 0)
      (effects (font (size 1.27 1.27) (thickness 0.15)) (justify left bottom) hide)
    )
    (property "MPN" "WSLP1206R0200FEA" (at 270.51 232.41 0)
      (effects (font (size 1.27 1.27) (thickness 0.15)) (justify left bottom) hide)
    )
    (property "Manufacturer" "Vishay" (at 270.51 234.95 0)
      (effects (font (size 1.27 1.27) (thickness 0.15)) (justify left bottom) hide)
    )
    (property "License" "Apache-2.0" (at 270.51 237.49 0)
      (effects (font (size 1.27 1.27) (thickness 0.15)) (justify left bottom) hide)
    )
    (property "Val" "0R02" (at 252.73 208.28 0)
      (effects (font (size 1.27 1.27) (thickness 0.15)))
    )
    (property "Tolerance" "1%" (at 270.51 222.25 0)
      (effects (font (size 1.27 1.27)) (justify left bottom) hide)
    )
    (property "Author" "Antmicro" (at 270.51 240.03 0)
      (effects (font (size 1.27 1.27) (thickness 0.15)) (justify left bottom) hide)
    )
    (pin "1")
    (pin "2")
    (instances
      (project "thunderbolt-pcie-adapter"
        (path ""
          (reference "R45") (unit 1)
        )
      )
    )
  )

  (symbol (lib_id "antmicroResistors0402:R_100k_0402") (at 137.16 149.86 0) (unit 1)
    (in_bom yes) (on_board yes) (dnp no)
    (property "Reference" "R34" (at 139.7 147.955 0)
      (effects (font (size 1.27 1.27) (thickness 0.15)))
    )
    (property "Value" "R_100k_0402" (at 157.48 162.56 0)
      (effects (font (size 1.27 1.27) (thickness 0.15)) (justify left bottom) hide)
    )
    (property "Footprint" "antmicro-footprints:R_0402_1005Metric" (at 157.48 165.1 0)
      (effects (font (size 1.27 1.27) (thickness 0.15)) (justify left bottom) hide)
    )
    (property "Datasheet" "https://www.bourns.com/docs/product-datasheets/cr.pdf" (at 157.48 167.64 0)
      (effects (font (size 1.27 1.27) (thickness 0.15)) (justify left bottom) hide)
    )
    (property "MPN" "CR0402-FX-1003GLF" (at 157.48 170.18 0)
      (effects (font (size 1.27 1.27) (thickness 0.15)) (justify left bottom) hide)
    )
    (property "Manufacturer" "Bourns" (at 157.48 172.72 0)
      (effects (font (size 1.27 1.27) (thickness 0.15)) (justify left bottom) hide)
    )
    (property "License" "Apache-2.0" (at 157.48 175.26 0)
      (effects (font (size 1.27 1.27) (thickness 0.15)) (justify left bottom) hide)
    )
    (property "Val" "100k" (at 141.605 149.225 0)
      (effects (font (size 1.27 1.27) (thickness 0.15)) (justify left bottom))
    )
    (property "Tolerance" "1%" (at 157.48 160.02 0)
      (effects (font (size 1.27 1.27)) (justify left bottom) hide)
    )
    (property "Author" "Antmicro" (at 157.48 177.8 0)
      (effects (font (size 1.27 1.27) (thickness 0.15)) (justify left bottom) hide)
    )
    (pin "1")
    (pin "2")
    (instances
      (project "thunderbolt-pcie-adapter"
        (path ""
          (reference "R34") (unit 1)
        )
      )
    )
  )

  (symbol (lib_id "antmicropower:GND") (at 64.77 35.56 0) (unit 1)
    (in_bom yes) (on_board yes) (dnp no)
    (property "Reference" "#PWR017" (at 64.77 41.91 0)
      (effects (font (size 1.27 1.27)) hide)
    )
    (property "Value" "GND" (at 62.865 40.005 0)
      (effects (font (size 1.27 1.27) (thickness 0.15)) (justify left bottom))
    )
    (property "Footprint" "" (at 64.77 35.56 0)
      (effects (font (size 1.27 1.27) (thickness 0.15)) (justify left bottom) hide)
    )
    (property "Datasheet" "" (at 64.77 35.56 0)
      (effects (font (size 1.27 1.27) (thickness 0.15)) (justify left bottom) hide)
    )
    (property "Author" "Antmicro" (at 73.66 43.18 0)
      (effects (font (size 1.27 1.27) (thickness 0.15)) (justify left bottom) hide)
    )
    (property "License" "Apache-2.0" (at 73.66 45.72 0)
      (effects (font (size 1.27 1.27) (thickness 0.15)) (justify left bottom) hide)
    )
    (pin "1")
    (instances
      (project "thunderbolt-pcie-adapter"
        (path ""
          (reference "#PWR017") (unit 1)
        )
      )
    )
  )

  (symbol (lib_id "antmicropower:GND") (at 142.24 55.88 90) (unit 1)
    (in_bom yes) (on_board yes) (dnp no)
    (property "Reference" "#PWR042" (at 148.59 55.88 0)
      (effects (font (size 1.27 1.27)) hide)
    )
    (property "Value" "GND" (at 146.685 57.785 0)
      (effects (font (size 1.27 1.27) (thickness 0.15)) (justify left bottom))
    )
    (property "Footprint" "" (at 142.24 55.88 0)
      (effects (font (size 1.27 1.27) (thickness 0.15)) (justify left bottom) hide)
    )
    (property "Datasheet" "" (at 142.24 55.88 0)
      (effects (font (size 1.27 1.27) (thickness 0.15)) (justify left bottom) hide)
    )
    (property "Author" "Antmicro" (at 149.86 46.99 0)
      (effects (font (size 1.27 1.27) (thickness 0.15)) (justify left bottom) hide)
    )
    (property "License" "Apache-2.0" (at 152.4 46.99 0)
      (effects (font (size 1.27 1.27) (thickness 0.15)) (justify left bottom) hide)
    )
    (pin "1")
    (instances
      (project "thunderbolt-pcie-adapter"
        (path ""
          (reference "#PWR042") (unit 1)
        )
      )
    )
  )

  (symbol (lib_id "antmicroResistors0402:R_100k_0402") (at 137.16 144.78 0) (unit 1)
    (in_bom yes) (on_board yes) (dnp no)
    (property "Reference" "R33" (at 139.7 142.875 0)
      (effects (font (size 1.27 1.27) (thickness 0.15)))
    )
    (property "Value" "R_100k_0402" (at 157.48 157.48 0)
      (effects (font (size 1.27 1.27) (thickness 0.15)) (justify left bottom) hide)
    )
    (property "Footprint" "antmicro-footprints:R_0402_1005Metric" (at 157.48 160.02 0)
      (effects (font (size 1.27 1.27) (thickness 0.15)) (justify left bottom) hide)
    )
    (property "Datasheet" "https://www.bourns.com/docs/product-datasheets/cr.pdf" (at 157.48 162.56 0)
      (effects (font (size 1.27 1.27) (thickness 0.15)) (justify left bottom) hide)
    )
    (property "MPN" "CR0402-FX-1003GLF" (at 157.48 165.1 0)
      (effects (font (size 1.27 1.27) (thickness 0.15)) (justify left bottom) hide)
    )
    (property "Manufacturer" "Bourns" (at 157.48 167.64 0)
      (effects (font (size 1.27 1.27) (thickness 0.15)) (justify left bottom) hide)
    )
    (property "License" "Apache-2.0" (at 157.48 170.18 0)
      (effects (font (size 1.27 1.27) (thickness 0.15)) (justify left bottom) hide)
    )
    (property "Val" "100k" (at 141.605 144.145 0)
      (effects (font (size 1.27 1.27) (thickness 0.15)) (justify left bottom))
    )
    (property "Tolerance" "1%" (at 157.48 154.94 0)
      (effects (font (size 1.27 1.27)) (justify left bottom) hide)
    )
    (property "Author" "Antmicro" (at 157.48 172.72 0)
      (effects (font (size 1.27 1.27) (thickness 0.15)) (justify left bottom) hide)
    )
    (pin "1")
    (pin "2")
    (instances
      (project "thunderbolt-pcie-adapter"
        (path ""
          (reference "R33") (unit 1)
        )
      )
    )
  )

  (symbol (lib_id "antmicroCapacitors0603:C_22u_0603") (at 349.25 71.12 90) (unit 1)
    (in_bom yes) (on_board yes) (dnp no)
    (property "Reference" "C41" (at 349.885 66.675 90)
      (effects (font (size 1.27 1.27) (thickness 0.15)) (justify right))
    )
    (property "Value" "C_22u_0603" (at 359.41 50.8 0)
      (effects (font (size 1.27 1.27) (thickness 0.15)) (justify left bottom) hide)
    )
    (property "Footprint" "antmicro-footprints:C_0603_1608Metric" (at 361.95 50.8 0)
      (effects (font (size 1.27 1.27) (thickness 0.15)) (justify left bottom) hide)
    )
    (property "Datasheet" "https://www.murata.com/products/productdetail?partno=GRM188R60J226MEA0%23" (at 364.49 50.8 0)
      (effects (font (size 1.27 1.27) (thickness 0.15)) (justify left bottom) hide)
    )
    (property "MPN" "GRM188R60J226MEA0D" (at 367.03 50.8 0)
      (effects (font (size 1.27 1.27) (thickness 0.15)) (justify left bottom) hide)
    )
    (property "Manufacturer" "Murata" (at 369.57 50.8 0)
      (effects (font (size 1.27 1.27) (thickness 0.15)) (justify left bottom) hide)
    )
    (property "License" "Apache-2.0" (at 372.11 50.8 0)
      (effects (font (size 1.27 1.27) (thickness 0.15)) (justify left bottom) hide)
    )
    (property "Val" "22u" (at 354.33 69.215 90)
      (effects (font (size 1.27 1.27) (thickness 0.15)) (justify left bottom))
    )
    (property "Voltage" "" (at 377.19 50.8 0)
      (effects (font (size 1.27 1.27)) (justify left bottom) hide)
    )
    (property "Dielectric" "" (at 379.73 50.8 0)
      (effects (font (size 1.27 1.27)) (justify left bottom) hide)
    )
    (property "Author" "Antmicro" (at 374.65 50.8 0)
      (effects (font (size 1.27 1.27) (thickness 0.15)) (justify left bottom) hide)
    )
    (pin "1")
    (pin "2")
    (instances
      (project "thunderbolt-pcie-adapter"
        (path ""
          (reference "C41") (unit 1)
        )
      )
    )
  )

  (symbol (lib_id "antmicroTestPoints:TP_1mm_SMD") (at 262.89 41.91 90) (unit 1)
    (in_bom no) (on_board yes) (dnp no)
    (property "Reference" "TP2" (at 260.985 36.83 90)
      (effects (font (size 1.27 1.27) (thickness 0.15)) (justify right))
    )
    (property "Value" "TP_1mm_SMD" (at 270.51 26.67 0)
      (effects (font (size 1.27 1.27) (thickness 0.15)) (justify left bottom) hide)
    )
    (property "Footprint" "antmicro-footprints:TP_SMD_1mm" (at 273.05 26.67 0)
      (effects (font (size 1.27 1.27) (thickness 0.15)) (justify left bottom) hide)
    )
    (property "Datasheet" "" (at 275.59 24.13 0)
      (effects (font (size 1.27 1.27) (thickness 0.15)) (justify left bottom) hide)
    )
    (property "License" "Apache-2.0" (at 280.67 26.67 0)
      (effects (font (size 1.27 1.27) (thickness 0.15)) (justify left bottom) hide)
    )
    (property "Manufacturer" "" (at 262.89 41.91 0)
      (effects (font (size 1.27 1.27)) hide)
    )
    (property "MPN" "" (at 262.89 41.91 0)
      (effects (font (size 1.27 1.27)) hide)
    )
    (property "Author" "Antmicro" (at 278.13 26.67 0)
      (effects (font (size 1.27 1.27) (thickness 0.15)) (justify left bottom) hide)
    )
    (pin "1")
    (instances
      (project "thunderbolt-pcie-adapter"
        (path ""
          (reference "TP2") (unit 1)
        )
      )
    )
  )

  (symbol (lib_id "antmicropower:GND") (at 146.05 139.7 90) (unit 1)
    (in_bom yes) (on_board yes) (dnp no)
    (property "Reference" "#PWR049" (at 152.4 139.7 0)
      (effects (font (size 1.27 1.27)) hide)
    )
    (property "Value" "GND" (at 150.495 141.605 0)
      (effects (font (size 1.27 1.27) (thickness 0.15)) (justify left bottom))
    )
    (property "Footprint" "" (at 146.05 139.7 0)
      (effects (font (size 1.27 1.27) (thickness 0.15)) (justify left bottom) hide)
    )
    (property "Datasheet" "" (at 146.05 139.7 0)
      (effects (font (size 1.27 1.27) (thickness 0.15)) (justify left bottom) hide)
    )
    (property "Author" "Antmicro" (at 153.67 130.81 0)
      (effects (font (size 1.27 1.27) (thickness 0.15)) (justify left bottom) hide)
    )
    (property "License" "Apache-2.0" (at 156.21 130.81 0)
      (effects (font (size 1.27 1.27) (thickness 0.15)) (justify left bottom) hide)
    )
    (pin "1")
    (instances
      (project "thunderbolt-pcie-adapter"
        (path ""
          (reference "#PWR049") (unit 1)
        )
      )
    )
  )

  (symbol (lib_id "antmicroCapacitors0603:C_22u_16V_0603") (at 219.71 219.71 90) (unit 1)
    (in_bom yes) (on_board yes) (dnp no) (fields_autoplaced)
    (property "Reference" "C43" (at 222.25 215.8936 90)
      (effects (font (size 1.27 1.27) (thickness 0.15)) (justify right))
    )
    (property "Value" "C_22u_16V_0603" (at 229.87 199.39 0)
      (effects (font (size 1.27 1.27) (thickness 0.15)) (justify left bottom) hide)
    )
    (property "Footprint" "antmicro-footprints:C_0603_1608Metric" (at 232.41 199.39 0)
      (effects (font (size 1.27 1.27) (thickness 0.15)) (justify left bottom) hide)
    )
    (property "Datasheet" "https://product.samsungsem.com/mlcc/CL10A226MO7JZN.do" (at 234.95 199.39 0)
      (effects (font (size 1.27 1.27) (thickness 0.15)) (justify left bottom) hide)
    )
    (property "MPN" "CL10A226MO7JZNC" (at 237.49 199.39 0)
      (effects (font (size 1.27 1.27) (thickness 0.15)) (justify left bottom) hide)
    )
    (property "Manufacturer" "Samsung Electro-Mechanics" (at 240.03 199.39 0)
      (effects (font (size 1.27 1.27) (thickness 0.15)) (justify left bottom) hide)
    )
    (property "License" "Apache-2.0" (at 242.57 199.39 0)
      (effects (font (size 1.27 1.27) (thickness 0.15)) (justify left bottom) hide)
    )
    (property "Val" "22u" (at 222.25 218.4336 90)
      (effects (font (size 1.27 1.27) (thickness 0.15)) (justify right))
    )
    (property "Voltage" "16V" (at 247.65 199.39 0)
      (effects (font (size 1.27 1.27)) (justify left bottom) hide)
    )
    (property "Dielectric" "" (at 250.19 199.39 0)
      (effects (font (size 1.27 1.27)) (justify left bottom) hide)
    )
    (property "Author" "Antmicro" (at 245.11 199.39 0)
      (effects (font (size 1.27 1.27) (thickness 0.15)) (justify left bottom) hide)
    )
    (pin "1")
    (pin "2")
    (instances
      (project "thunderbolt-pcie-adapter"
        (path ""
          (reference "C43") (unit 1)
        )
      )
    )
  )

  (symbol (lib_id "antmicroResistors0402:R_40k2_0402") (at 339.09 66.04 90) (unit 1)
    (in_bom yes) (on_board yes) (dnp no)
    (property "Reference" "R36" (at 340.995 62.23 90)
      (effects (font (size 1.27 1.27) (thickness 0.15)) (justify right))
    )
    (property "Value" "R_40k2_0402" (at 351.79 45.72 0)
      (effects (font (size 1.27 1.27) (thickness 0.15)) (justify left bottom) hide)
    )
    (property "Footprint" "antmicro-footprints:R_0402_1005Metric" (at 354.33 45.72 0)
      (effects (font (size 1.27 1.27) (thickness 0.15)) (justify left bottom) hide)
    )
    (property "Datasheet" "https://www.bourns.com/docs/product-datasheets/cr.pdf" (at 356.87 45.72 0)
      (effects (font (size 1.27 1.27) (thickness 0.15)) (justify left bottom) hide)
    )
    (property "MPN" "CR0402-FX-4022GLF" (at 359.41 45.72 0)
      (effects (font (size 1.27 1.27) (thickness 0.15)) (justify left bottom) hide)
    )
    (property "Manufacturer" "Bourns" (at 361.95 45.72 0)
      (effects (font (size 1.27 1.27) (thickness 0.15)) (justify left bottom) hide)
    )
    (property "License" "Apache-2.0" (at 364.49 45.72 0)
      (effects (font (size 1.27 1.27) (thickness 0.15)) (justify left bottom) hide)
    )
    (property "Val" "40k2" (at 346.075 64.135 90)
      (effects (font (size 1.27 1.27) (thickness 0.15)) (justify left bottom))
    )
    (property "Tolerance" "1%" (at 349.25 45.72 0)
      (effects (font (size 1.27 1.27)) (justify left bottom) hide)
    )
    (property "Author" "Antmicro" (at 367.03 45.72 0)
      (effects (font (size 1.27 1.27) (thickness 0.15)) (justify left bottom) hide)
    )
    (pin "1")
    (pin "2")
    (instances
      (project "thunderbolt-pcie-adapter"
        (path ""
          (reference "R36") (unit 1)
        )
      )
    )
  )

  (symbol (lib_id "antmicroResistors0402:R_24k_0402") (at 104.14 213.36 90) (unit 1)
    (in_bom yes) (on_board yes) (dnp no) (fields_autoplaced)
    (property "Reference" "R7" (at 106.68 209.55 90)
      (effects (font (size 1.27 1.27) (thickness 0.15)) (justify right))
    )
    (property "Value" "R_24k_0402" (at 116.84 193.04 0)
      (effects (font (size 1.27 1.27) (thickness 0.15)) (justify left bottom) hide)
    )
    (property "Footprint" "antmicro-footprints:R_0402_1005Metric" (at 119.38 193.04 0)
      (effects (font (size 1.27 1.27) (thickness 0.15)) (justify left bottom) hide)
    )
    (property "Datasheet" "https://www.bourns.com/docs/product-datasheets/cr.pdf" (at 121.92 193.04 0)
      (effects (font (size 1.27 1.27) (thickness 0.15)) (justify left bottom) hide)
    )
    (property "MPN" "CR0402-FX-2402GLF" (at 124.46 193.04 0)
      (effects (font (size 1.27 1.27) (thickness 0.15)) (justify left bottom) hide)
    )
    (property "Manufacturer" "Bourns" (at 127 193.04 0)
      (effects (font (size 1.27 1.27) (thickness 0.15)) (justify left bottom) hide)
    )
    (property "License" "Apache-2.0" (at 129.54 193.04 0)
      (effects (font (size 1.27 1.27) (thickness 0.15)) (justify left bottom) hide)
    )
    (property "Val" "24k" (at 106.68 212.09 90)
      (effects (font (size 1.27 1.27) (thickness 0.15)) (justify right))
    )
    (property "Tolerance" "1%" (at 114.3 193.04 0)
      (effects (font (size 1.27 1.27)) (justify left bottom) hide)
    )
    (property "Author" "Antmicro" (at 132.08 193.04 0)
      (effects (font (size 1.27 1.27) (thickness 0.15)) (justify left bottom) hide)
    )
    (pin "1")
    (pin "2")
    (instances
      (project "thunderbolt-pcie-adapter"
        (path ""
          (reference "R7") (unit 1)
        )
      )
    )
  )

  (symbol (lib_id "antmicropower:GND") (at 331.47 171.45 0) (unit 1)
    (in_bom yes) (on_board yes) (dnp no)
    (property "Reference" "#PWR075" (at 331.47 177.8 0)
      (effects (font (size 1.27 1.27)) hide)
    )
    (property "Value" "GND" (at 329.565 175.895 0)
      (effects (font (size 1.27 1.27) (thickness 0.15)) (justify left bottom))
    )
    (property "Footprint" "" (at 331.47 171.45 0)
      (effects (font (size 1.27 1.27) (thickness 0.15)) (justify left bottom) hide)
    )
    (property "Datasheet" "" (at 331.47 171.45 0)
      (effects (font (size 1.27 1.27) (thickness 0.15)) (justify left bottom) hide)
    )
    (property "Author" "Antmicro" (at 340.36 179.07 0)
      (effects (font (size 1.27 1.27) (thickness 0.15)) (justify left bottom) hide)
    )
    (property "License" "Apache-2.0" (at 340.36 181.61 0)
      (effects (font (size 1.27 1.27) (thickness 0.15)) (justify left bottom) hide)
    )
    (pin "1")
    (instances
      (project "thunderbolt-pcie-adapter"
        (path ""
          (reference "#PWR075") (unit 1)
        )
      )
    )
  )

  (symbol (lib_id "antmicroCapacitors0402:C_220n_0402") (at 119.38 252.73 270) (mirror x) (unit 1)
    (in_bom yes) (on_board yes) (dnp no) (fields_autoplaced)
    (property "Reference" "C16" (at 116.84 248.9136 90)
      (effects (font (size 1.27 1.27) (thickness 0.15)) (justify right))
    )
    (property "Value" "C_220n_0402" (at 109.22 232.41 0)
      (effects (font (size 1.27 1.27) (thickness 0.15)) (justify left bottom) hide)
    )
    (property "Footprint" "antmicro-footprints:C_0402_1005Metric" (at 106.68 232.41 0)
      (effects (font (size 1.27 1.27) (thickness 0.15)) (justify left bottom) hide)
    )
    (property "Datasheet" "https://www.yageo.com/en/Chart/Download/pdf/CC0402KRX5R6BB224" (at 104.14 232.41 0)
      (effects (font (size 1.27 1.27) (thickness 0.15)) (justify left bottom) hide)
    )
    (property "MPN" "CC0402KRX5R6BB224" (at 101.6 232.41 0)
      (effects (font (size 1.27 1.27) (thickness 0.15)) (justify left bottom) hide)
    )
    (property "Manufacturer" "YAGEO" (at 99.06 232.41 0)
      (effects (font (size 1.27 1.27) (thickness 0.15)) (justify left bottom) hide)
    )
    (property "License" "Apache-2.0" (at 96.52 232.41 0)
      (effects (font (size 1.27 1.27) (thickness 0.15)) (justify left bottom) hide)
    )
    (property "Val" "220n" (at 116.84 251.4536 90)
      (effects (font (size 1.27 1.27) (thickness 0.15)) (justify right))
    )
    (property "Voltage" "" (at 91.44 232.41 0)
      (effects (font (size 1.27 1.27)) (justify left bottom) hide)
    )
    (property "Dielectric" "" (at 88.9 232.41 0)
      (effects (font (size 1.27 1.27)) (justify left bottom) hide)
    )
    (property "Author" "Antmicro" (at 93.98 232.41 0)
      (effects (font (size 1.27 1.27) (thickness 0.15)) (justify left bottom) hide)
    )
    (pin "1")
    (pin "2")
    (instances
      (project "thunderbolt-pcie-adapter"
        (path ""
          (reference "C16") (unit 1)
        )
      )
    )
  )

  (symbol (lib_id "antmicropower:GND") (at 365.76 76.2 0) (unit 1)
    (in_bom yes) (on_board yes) (dnp no)
    (property "Reference" "#PWR068" (at 365.76 82.55 0)
      (effects (font (size 1.27 1.27)) hide)
    )
    (property "Value" "GND" (at 363.855 80.645 0)
      (effects (font (size 1.27 1.27) (thickness 0.15)) (justify left bottom))
    )
    (property "Footprint" "" (at 365.76 76.2 0)
      (effects (font (size 1.27 1.27) (thickness 0.15)) (justify left bottom) hide)
    )
    (property "Datasheet" "" (at 365.76 76.2 0)
      (effects (font (size 1.27 1.27) (thickness 0.15)) (justify left bottom) hide)
    )
    (property "Author" "Antmicro" (at 374.65 83.82 0)
      (effects (font (size 1.27 1.27) (thickness 0.15)) (justify left bottom) hide)
    )
    (property "License" "Apache-2.0" (at 374.65 86.36 0)
      (effects (font (size 1.27 1.27) (thickness 0.15)) (justify left bottom) hide)
    )
    (pin "1")
    (instances
      (project "thunderbolt-pcie-adapter"
        (path ""
          (reference "#PWR068") (unit 1)
        )
      )
    )
  )

  (symbol (lib_id "antmicropower:GND") (at 287.02 76.2 0) (unit 1)
    (in_bom yes) (on_board yes) (dnp no)
    (property "Reference" "#PWR0145" (at 287.02 82.55 0)
      (effects (font (size 1.27 1.27)) hide)
    )
    (property "Value" "GND" (at 285.115 80.645 0)
      (effects (font (size 1.27 1.27) (thickness 0.15)) (justify left bottom))
    )
    (property "Footprint" "" (at 287.02 76.2 0)
      (effects (font (size 1.27 1.27) (thickness 0.15)) (justify left bottom) hide)
    )
    (property "Datasheet" "" (at 287.02 76.2 0)
      (effects (font (size 1.27 1.27) (thickness 0.15)) (justify left bottom) hide)
    )
    (property "Author" "Antmicro" (at 295.91 83.82 0)
      (effects (font (size 1.27 1.27) (thickness 0.15)) (justify left bottom) hide)
    )
    (property "License" "Apache-2.0" (at 295.91 86.36 0)
      (effects (font (size 1.27 1.27) (thickness 0.15)) (justify left bottom) hide)
    )
    (pin "1")
    (instances
      (project "thunderbolt-pcie-adapter"
        (path ""
          (reference "#PWR0145") (unit 1)
        )
      )
    )
  )

  (symbol (lib_id "antmicroResistors0402:R_0R_0402") (at 184.15 214.63 0) (unit 1)
    (in_bom yes) (on_board yes) (dnp no)
    (property "Reference" "R26" (at 186.69 217.17 0)
      (effects (font (size 1.27 1.27) (thickness 0.15)))
    )
    (property "Value" "R_0R_0402" (at 204.47 227.33 0)
      (effects (font (size 1.27 1.27) (thickness 0.15)) (justify left bottom) hide)
    )
    (property "Footprint" "antmicro-footprints:R_0402_1005Metric" (at 204.47 229.87 0)
      (effects (font (size 1.27 1.27) (thickness 0.15)) (justify left bottom) hide)
    )
    (property "Datasheet" "https://industrial.panasonic.com/cdbs/www-data/pdf/RDA0000/AOA0000C301.pdf" (at 204.47 232.41 0)
      (effects (font (size 1.27 1.27) (thickness 0.15)) (justify left bottom) hide)
    )
    (property "MPN" "ERJ2GE0R00X" (at 204.47 234.95 0)
      (effects (font (size 1.27 1.27) (thickness 0.15)) (justify left bottom) hide)
    )
    (property "Manufacturer" "Panasonic" (at 204.47 237.49 0)
      (effects (font (size 1.27 1.27) (thickness 0.15)) (justify left bottom) hide)
    )
    (property "License" "Apache-2.0" (at 204.47 240.03 0)
      (effects (font (size 1.27 1.27) (thickness 0.15)) (justify left bottom) hide)
    )
    (property "Val" "0R" (at 185.42 215.265 0)
      (effects (font (size 1.27 1.27) (thickness 0.15)) (justify left bottom))
    )
    (property "Tolerance" "~" (at 204.47 224.79 0)
      (effects (font (size 1.27 1.27)) (justify left bottom) hide)
    )
    (property "Current" "1A" (at 204.47 245.11 0)
      (effects (font (size 1.27 1.27) (thickness 0.15)) (justify left bottom) hide)
    )
    (property "Author" "Antmicro" (at 204.47 242.57 0)
      (effects (font (size 1.27 1.27) (thickness 0.15)) (justify left bottom) hide)
    )
    (pin "1")
    (pin "2")
    (instances
      (project "thunderbolt-pcie-adapter"
        (path ""
          (reference "R26") (unit 1)
        )
      )
    )
  )

  (symbol (lib_id "antmicroCapacitors0603:C_22u_16V_0603") (at 270.51 222.25 90) (unit 1)
    (in_bom yes) (on_board yes) (dnp no)
    (property "Reference" "C50" (at 273.05 218.4336 90)
      (effects (font (size 1.27 1.27) (thickness 0.15)) (justify right))
    )
    (property "Value" "C_22u_16V_0603" (at 280.67 201.93 0)
      (effects (font (size 1.27 1.27) (thickness 0.15)) (justify left bottom) hide)
    )
    (property "Footprint" "antmicro-footprints:C_0603_1608Metric" (at 283.21 201.93 0)
      (effects (font (size 1.27 1.27) (thickness 0.15)) (justify left bottom) hide)
    )
    (property "Datasheet" "https://product.samsungsem.com/mlcc/CL10A226MO7JZN.do" (at 285.75 201.93 0)
      (effects (font (size 1.27 1.27) (thickness 0.15)) (justify left bottom) hide)
    )
    (property "MPN" "CL10A226MO7JZNC" (at 288.29 201.93 0)
      (effects (font (size 1.27 1.27) (thickness 0.15)) (justify left bottom) hide)
    )
    (property "Manufacturer" "Samsung Electro-Mechanics" (at 290.83 201.93 0)
      (effects (font (size 1.27 1.27) (thickness 0.15)) (justify left bottom) hide)
    )
    (property "License" "Apache-2.0" (at 293.37 201.93 0)
      (effects (font (size 1.27 1.27) (thickness 0.15)) (justify left bottom) hide)
    )
    (property "Val" "22u" (at 273.05 220.9736 90)
      (effects (font (size 1.27 1.27) (thickness 0.15)) (justify right))
    )
    (property "Voltage" "16V" (at 298.45 201.93 0)
      (effects (font (size 1.27 1.27)) (justify left bottom) hide)
    )
    (property "Dielectric" "" (at 300.99 201.93 0)
      (effects (font (size 1.27 1.27)) (justify left bottom) hide)
    )
    (property "Author" "Antmicro" (at 295.91 201.93 0)
      (effects (font (size 1.27 1.27) (thickness 0.15)) (justify left bottom) hide)
    )
    (pin "1")
    (pin "2")
    (instances
      (project "thunderbolt-pcie-adapter"
        (path ""
          (reference "C50") (unit 1)
        )
      )
    )
  )

  (symbol (lib_id "antmicroCapacitorsmisc:C_22u_1206_35V") (at 53.34 213.36 90) (unit 1)
    (in_bom yes) (on_board yes) (dnp no) (fields_autoplaced)
    (property "Reference" "C8" (at 55.88 209.5436 90)
      (effects (font (size 1.27 1.27) (thickness 0.15)) (justify right))
    )
    (property "Value" "C_22u_1206_35V" (at 63.5 193.04 0)
      (effects (font (size 1.27 1.27) (thickness 0.15)) (justify left bottom) hide)
    )
    (property "Footprint" "antmicro-footprints:C_1206_3216Metric" (at 66.04 193.04 0)
      (effects (font (size 1.27 1.27) (thickness 0.15)) (justify left bottom) hide)
    )
    (property "Datasheet" "https://product.tdk.com/en/search/capacitor/ceramic/mlcc/info?part_no=3216X5R1V226M160AC" (at 68.58 193.04 0)
      (effects (font (size 1.27 1.27) (thickness 0.15)) (justify left bottom) hide)
    )
    (property "MPN" "3216X5R1V226M160AC" (at 71.12 193.04 0)
      (effects (font (size 1.27 1.27) (thickness 0.15)) (justify left bottom) hide)
    )
    (property "Manufacturer" "TDK" (at 73.66 193.04 0)
      (effects (font (size 1.27 1.27) (thickness 0.15)) (justify left bottom) hide)
    )
    (property "License" "Apache-2.0" (at 76.2 193.04 0)
      (effects (font (size 1.27 1.27) (thickness 0.15)) (justify left bottom) hide)
    )
    (property "Val" "22u" (at 55.88 212.0836 90)
      (effects (font (size 1.27 1.27) (thickness 0.15)) (justify right))
    )
    (property "Voltage" "35V" (at 81.28 193.04 0)
      (effects (font (size 1.27 1.27)) (justify left bottom) hide)
    )
    (property "Dielectric" "" (at 83.82 193.04 0)
      (effects (font (size 1.27 1.27)) (justify left bottom) hide)
    )
    (property "Author" "Antmicro" (at 78.74 193.04 0)
      (effects (font (size 1.27 1.27) (thickness 0.15)) (justify left bottom) hide)
    )
    (pin "1")
    (pin "2")
    (instances
      (project "thunderbolt-pcie-adapter"
        (path ""
          (reference "C8") (unit 1)
        )
      )
    )
  )

  (symbol (lib_id "antmicroFixedInductors:L_6u8_12.8A_Coilcraft-XAL7070") (at 179.07 238.76 270) (unit 1)
    (in_bom yes) (on_board yes) (dnp no) (fields_autoplaced)
    (property "Reference" "L1" (at 180.34 240.03 90)
      (effects (font (size 1.27 1.27) (thickness 0.15)) (justify left))
    )
    (property "Value" "L_6u8_12.8A_Coilcraft-XAL7070" (at 176.53 252.73 0)
      (effects (font (size 1.27 1.27) (thickness 0.15)) (justify left bottom) hide)
    )
    (property "Footprint" "antmicro-footprints:L_Coilcraft-XAL7070" (at 171.45 252.73 0)
      (effects (font (size 1.27 1.27) (thickness 0.15)) (justify left bottom) hide)
    )
    (property "Datasheet" "https://www.coilcraft.com/en-us/products/power/shielded-inductors/molded-inductor/xal/xal7070/xal7070-682" (at 168.91 252.73 0)
      (effects (font (size 1.27 1.27) (thickness 0.15)) (justify left bottom) hide)
    )
    (property "Val" "6u8/12.8A" (at 180.34 242.57 90)
      (effects (font (size 1.27 1.27) (thickness 0.15)) (justify left))
    )
    (property "Manufacturer" "Coilcraft" (at 166.37 252.73 0)
      (effects (font (size 1.27 1.27) (thickness 0.15)) (justify left bottom) hide)
    )
    (property "MPN" "XAL7070-682MEC" (at 163.83 252.73 0)
      (effects (font (size 1.27 1.27) (thickness 0.15)) (justify left bottom) hide)
    )
    (property "ISat" "12.8 A" (at 162.56 252.73 0)
      (effects (font (size 1.27 1.27)) (justify left) hide)
    )
    (property "IMax" "9.2 A" (at 158.75 252.73 0)
      (effects (font (size 1.27 1.27) (thickness 0.15)) (justify left bottom) hide)
    )
    (property "Size" "7.7x8" (at 156.21 252.73 0)
      (effects (font (size 1.27 1.27) (thickness 0.15)) (justify left bottom) hide)
    )
    (property "License" "Apache-2.0" (at 151.13 252.73 0)
      (effects (font (size 1.27 1.27) (thickness 0.15)) (justify left bottom) hide)
    )
    (property "Author" "Antmicro" (at 153.67 252.73 0)
      (effects (font (size 1.27 1.27) (thickness 0.15)) (justify left bottom) hide)
    )
    (pin "1")
    (pin "2")
    (instances
      (project "thunderbolt-pcie-adapter"
        (path ""
          (reference "L1") (unit 1)
        )
      )
    )
  )

  (symbol (lib_id "antmicroResistors0402:R_15k_0.1%_0402") (at 137.16 154.94 0) (unit 1)
    (in_bom yes) (on_board yes) (dnp no)
    (property "Reference" "R35" (at 139.7 153.035 0)
      (effects (font (size 1.27 1.27) (thickness 0.15)))
    )
    (property "Value" "R_15k_0.1%_0402" (at 157.48 167.64 0)
      (effects (font (size 1.27 1.27) (thickness 0.15)) (justify left bottom) hide)
    )
    (property "Footprint" "antmicro-footprints:R_0402_1005Metric" (at 157.48 170.18 0)
      (effects (font (size 1.27 1.27) (thickness 0.15)) (justify left bottom) hide)
    )
    (property "Datasheet" "https://www.mouser.com/datasheet/2/315/AOA0000C307-1149632.pdf" (at 157.48 172.72 0)
      (effects (font (size 1.27 1.27) (thickness 0.15)) (justify left bottom) hide)
    )
    (property "MPN" "ERA-2ARB153X" (at 157.48 175.26 0)
      (effects (font (size 1.27 1.27) (thickness 0.15)) (justify left bottom) hide)
    )
    (property "Manufacturer" "Panasonic" (at 157.48 177.8 0)
      (effects (font (size 1.27 1.27) (thickness 0.15)) (justify left bottom) hide)
    )
    (property "License" "Apache-2.0" (at 157.48 180.34 0)
      (effects (font (size 1.27 1.27) (thickness 0.15)) (justify left bottom) hide)
    )
    (property "Val" "15k" (at 137.795 158.115 0)
      (effects (font (size 1.27 1.27) (thickness 0.15)) (justify left bottom))
    )
    (property "Tolerance" "0.1%" (at 157.48 165.1 0)
      (effects (font (size 1.27 1.27)) (justify left bottom) hide)
    )
    (property "Author" "Antmicro" (at 157.48 182.88 0)
      (effects (font (size 1.27 1.27) (thickness 0.15)) (justify left bottom) hide)
    )
    (pin "1")
    (pin "2")
    (instances
      (project "thunderbolt-pcie-adapter"
        (path ""
          (reference "R35") (unit 1)
        )
      )
    )
  )

  (symbol (lib_id "antmicroResistors0402:R_100k_0402") (at 135.89 220.98 270) (unit 1)
    (in_bom yes) (on_board yes) (dnp no) (fields_autoplaced)
    (property "Reference" "R22" (at 133.35 222.25 90)
      (effects (font (size 1.27 1.27) (thickness 0.15)) (justify right))
    )
    (property "Value" "R_100k_0402" (at 123.19 241.3 0)
      (effects (font (size 1.27 1.27) (thickness 0.15)) (justify left bottom) hide)
    )
    (property "Footprint" "antmicro-footprints:R_0402_1005Metric" (at 120.65 241.3 0)
      (effects (font (size 1.27 1.27) (thickness 0.15)) (justify left bottom) hide)
    )
    (property "Datasheet" "https://www.bourns.com/docs/product-datasheets/cr.pdf" (at 118.11 241.3 0)
      (effects (font (size 1.27 1.27) (thickness 0.15)) (justify left bottom) hide)
    )
    (property "MPN" "CR0402-FX-1003GLF" (at 115.57 241.3 0)
      (effects (font (size 1.27 1.27) (thickness 0.15)) (justify left bottom) hide)
    )
    (property "Manufacturer" "Bourns" (at 113.03 241.3 0)
      (effects (font (size 1.27 1.27) (thickness 0.15)) (justify left bottom) hide)
    )
    (property "License" "Apache-2.0" (at 110.49 241.3 0)
      (effects (font (size 1.27 1.27) (thickness 0.15)) (justify left bottom) hide)
    )
    (property "Val" "100k" (at 133.35 224.79 90)
      (effects (font (size 1.27 1.27) (thickness 0.15)) (justify right))
    )
    (property "Tolerance" "1%" (at 125.73 241.3 0)
      (effects (font (size 1.27 1.27)) (justify left bottom) hide)
    )
    (property "Author" "Antmicro" (at 107.95 241.3 0)
      (effects (font (size 1.27 1.27) (thickness 0.15)) (justify left bottom) hide)
    )
    (pin "1")
    (pin "2")
    (instances
      (project "thunderbolt-pcie-adapter"
        (path ""
          (reference "R22") (unit 1)
        )
      )
    )
  )

  (symbol (lib_id "antmicroResistors0402:R_100k_0402") (at 137.16 124.46 0) (unit 1)
    (in_bom yes) (on_board yes) (dnp no)
    (property "Reference" "R30" (at 139.7 126.365 0)
      (effects (font (size 1.27 1.27) (thickness 0.15)))
    )
    (property "Value" "R_100k_0402" (at 157.48 137.16 0)
      (effects (font (size 1.27 1.27) (thickness 0.15)) (justify left bottom) hide)
    )
    (property "Footprint" "antmicro-footprints:R_0402_1005Metric" (at 157.48 139.7 0)
      (effects (font (size 1.27 1.27) (thickness 0.15)) (justify left bottom) hide)
    )
    (property "Datasheet" "https://www.bourns.com/docs/product-datasheets/cr.pdf" (at 157.48 142.24 0)
      (effects (font (size 1.27 1.27) (thickness 0.15)) (justify left bottom) hide)
    )
    (property "MPN" "CR0402-FX-1003GLF" (at 157.48 144.78 0)
      (effects (font (size 1.27 1.27) (thickness 0.15)) (justify left bottom) hide)
    )
    (property "Manufacturer" "Bourns" (at 157.48 147.32 0)
      (effects (font (size 1.27 1.27) (thickness 0.15)) (justify left bottom) hide)
    )
    (property "License" "Apache-2.0" (at 157.48 149.86 0)
      (effects (font (size 1.27 1.27) (thickness 0.15)) (justify left bottom) hide)
    )
    (property "Val" "100k" (at 141.605 123.825 0)
      (effects (font (size 1.27 1.27) (thickness 0.15)) (justify left bottom))
    )
    (property "Tolerance" "1%" (at 157.48 134.62 0)
      (effects (font (size 1.27 1.27)) (justify left bottom) hide)
    )
    (property "Author" "Antmicro" (at 157.48 152.4 0)
      (effects (font (size 1.27 1.27) (thickness 0.15)) (justify left bottom) hide)
    )
    (pin "1")
    (pin "2")
    (instances
      (project "thunderbolt-pcie-adapter"
        (path ""
          (reference "R30") (unit 1)
        )
      )
    )
  )

  (symbol (lib_id "antmicroCapacitors0402:C_100n_0402") (at 180.34 215.9 270) (unit 1)
    (in_bom yes) (on_board yes) (dnp no) (fields_autoplaced)
    (property "Reference" "C29" (at 177.8 217.1763 90)
      (effects (font (size 1.27 1.27) (thickness 0.15)) (justify right))
    )
    (property "Value" "C_100n_0402" (at 170.18 236.22 0)
      (effects (font (size 1.27 1.27) (thickness 0.15)) (justify left bottom) hide)
    )
    (property "Footprint" "antmicro-footprints:C_0402_1005Metric" (at 167.64 236.22 0)
      (effects (font (size 1.27 1.27) (thickness 0.15)) (justify left bottom) hide)
    )
    (property "Datasheet" "https://www.murata.com/products/productdetail?partno=GRM155R61H104KE14%23" (at 165.1 236.22 0)
      (effects (font (size 1.27 1.27) (thickness 0.15)) (justify left bottom) hide)
    )
    (property "MPN" "GRM155R61H104KE14D" (at 162.56 236.22 0)
      (effects (font (size 1.27 1.27) (thickness 0.15)) (justify left bottom) hide)
    )
    (property "Manufacturer" "Murata" (at 160.02 236.22 0)
      (effects (font (size 1.27 1.27) (thickness 0.15)) (justify left bottom) hide)
    )
    (property "License" "Apache-2.0" (at 157.48 236.22 0)
      (effects (font (size 1.27 1.27) (thickness 0.15)) (justify left bottom) hide)
    )
    (property "Val" "100n" (at 177.8 219.7163 90)
      (effects (font (size 1.27 1.27) (thickness 0.15)) (justify right))
    )
    (property "Voltage" "50V" (at 152.4 236.22 0)
      (effects (font (size 1.27 1.27)) (justify left bottom) hide)
    )
    (property "Dielectric" "X5R" (at 149.86 236.22 0)
      (effects (font (size 1.27 1.27)) (justify left bottom) hide)
    )
    (property "Author" "Antmicro" (at 154.94 236.22 0)
      (effects (font (size 1.27 1.27) (thickness 0.15)) (justify left bottom) hide)
    )
    (pin "1")
    (pin "2")
    (instances
      (project "thunderbolt-pcie-adapter"
        (path ""
          (reference "C29") (unit 1)
        )
      )
    )
  )

  (symbol (lib_id "antmicroResistors0402:R_2k2_0402") (at 251.46 170.18 90) (unit 1)
    (in_bom yes) (on_board yes) (dnp no) (fields_autoplaced)
    (property "Reference" "R97" (at 253.365 166.37 90)
      (effects (font (size 1.27 1.27) (thickness 0.15)) (justify right))
    )
    (property "Value" "R_2k2_0402" (at 264.16 149.86 0)
      (effects (font (size 1.27 1.27) (thickness 0.15)) (justify left bottom) hide)
    )
    (property "Footprint" "antmicro-footprints:R_0402_1005Metric" (at 266.7 149.86 0)
      (effects (font (size 1.27 1.27) (thickness 0.15)) (justify left bottom) hide)
    )
    (property "Datasheet" "https://www.bourns.com/docs/product-datasheets/cr.pdf" (at 269.24 149.86 0)
      (effects (font (size 1.27 1.27) (thickness 0.15)) (justify left bottom) hide)
    )
    (property "MPN" "CR0402-FX-2201GLF" (at 271.78 149.86 0)
      (effects (font (size 1.27 1.27) (thickness 0.15)) (justify left bottom) hide)
    )
    (property "Manufacturer" "Bourns" (at 274.32 149.86 0)
      (effects (font (size 1.27 1.27) (thickness 0.15)) (justify left bottom) hide)
    )
    (property "License" "Apache-2.0" (at 276.86 149.86 0)
      (effects (font (size 1.27 1.27) (thickness 0.15)) (justify left bottom) hide)
    )
    (property "Val" "2k2" (at 253.365 168.91 90)
      (effects (font (size 1.27 1.27) (thickness 0.15)) (justify right))
    )
    (property "Tolerance" "1%" (at 261.62 149.86 0)
      (effects (font (size 1.27 1.27)) (justify left bottom) hide)
    )
    (property "Author" "Antmicro" (at 279.4 149.86 0)
      (effects (font (size 1.27 1.27) (thickness 0.15)) (justify left bottom) hide)
    )
    (pin "1")
    (pin "2")
    (instances
      (project "thunderbolt-pcie-adapter"
        (path ""
          (reference "R97") (unit 1)
        )
      )
    )
  )

  (symbol (lib_id "antmicropower:GND") (at 142.24 45.72 90) (unit 1)
    (in_bom yes) (on_board yes) (dnp no)
    (property "Reference" "#PWR041" (at 148.59 45.72 0)
      (effects (font (size 1.27 1.27)) hide)
    )
    (property "Value" "GND" (at 146.685 47.625 0)
      (effects (font (size 1.27 1.27) (thickness 0.15)) (justify left bottom))
    )
    (property "Footprint" "" (at 142.24 45.72 0)
      (effects (font (size 1.27 1.27) (thickness 0.15)) (justify left bottom) hide)
    )
    (property "Datasheet" "" (at 142.24 45.72 0)
      (effects (font (size 1.27 1.27) (thickness 0.15)) (justify left bottom) hide)
    )
    (property "Author" "Antmicro" (at 149.86 36.83 0)
      (effects (font (size 1.27 1.27) (thickness 0.15)) (justify left bottom) hide)
    )
    (property "License" "Apache-2.0" (at 152.4 36.83 0)
      (effects (font (size 1.27 1.27) (thickness 0.15)) (justify left bottom) hide)
    )
    (pin "1")
    (instances
      (project "thunderbolt-pcie-adapter"
        (path ""
          (reference "#PWR041") (unit 1)
        )
      )
    )
  )

  (symbol (lib_id "antmicroCapacitors0603:C_22u_16V_0603") (at 201.93 219.71 90) (unit 1)
    (in_bom yes) (on_board yes) (dnp no) (fields_autoplaced)
    (property "Reference" "C38" (at 204.47 215.8936 90)
      (effects (font (size 1.27 1.27) (thickness 0.15)) (justify right))
    )
    (property "Value" "C_22u_16V_0603" (at 212.09 199.39 0)
      (effects (font (size 1.27 1.27) (thickness 0.15)) (justify left bottom) hide)
    )
    (property "Footprint" "antmicro-footprints:C_0603_1608Metric" (at 214.63 199.39 0)
      (effects (font (size 1.27 1.27) (thickness 0.15)) (justify left bottom) hide)
    )
    (property "Datasheet" "https://product.samsungsem.com/mlcc/CL10A226MO7JZN.do" (at 217.17 199.39 0)
      (effects (font (size 1.27 1.27) (thickness 0.15)) (justify left bottom) hide)
    )
    (property "MPN" "CL10A226MO7JZNC" (at 219.71 199.39 0)
      (effects (font (size 1.27 1.27) (thickness 0.15)) (justify left bottom) hide)
    )
    (property "Manufacturer" "Samsung Electro-Mechanics" (at 222.25 199.39 0)
      (effects (font (size 1.27 1.27) (thickness 0.15)) (justify left bottom) hide)
    )
    (property "License" "Apache-2.0" (at 224.79 199.39 0)
      (effects (font (size 1.27 1.27) (thickness 0.15)) (justify left bottom) hide)
    )
    (property "Val" "22u" (at 204.47 218.4336 90)
      (effects (font (size 1.27 1.27) (thickness 0.15)) (justify right))
    )
    (property "Voltage" "16V" (at 229.87 199.39 0)
      (effects (font (size 1.27 1.27)) (justify left bottom) hide)
    )
    (property "Dielectric" "" (at 232.41 199.39 0)
      (effects (font (size 1.27 1.27)) (justify left bottom) hide)
    )
    (property "Author" "Antmicro" (at 227.33 199.39 0)
      (effects (font (size 1.27 1.27) (thickness 0.15)) (justify left bottom) hide)
    )
    (pin "1")
    (pin "2")
    (instances
      (project "thunderbolt-pcie-adapter"
        (path ""
          (reference "C38") (unit 1)
        )
      )
    )
  )

  (symbol (lib_id "antmicroCapacitors0603:C_22u_0603") (at 365.76 71.12 90) (unit 1)
    (in_bom yes) (on_board yes) (dnp no)
    (property "Reference" "C47" (at 366.395 66.675 90)
      (effects (font (size 1.27 1.27) (thickness 0.15)) (justify right))
    )
    (property "Value" "C_22u_0603" (at 375.92 50.8 0)
      (effects (font (size 1.27 1.27) (thickness 0.15)) (justify left bottom) hide)
    )
    (property "Footprint" "antmicro-footprints:C_0603_1608Metric" (at 378.46 50.8 0)
      (effects (font (size 1.27 1.27) (thickness 0.15)) (justify left bottom) hide)
    )
    (property "Datasheet" "https://www.murata.com/products/productdetail?partno=GRM188R60J226MEA0%23" (at 381 50.8 0)
      (effects (font (size 1.27 1.27) (thickness 0.15)) (justify left bottom) hide)
    )
    (property "MPN" "GRM188R60J226MEA0D" (at 383.54 50.8 0)
      (effects (font (size 1.27 1.27) (thickness 0.15)) (justify left bottom) hide)
    )
    (property "Manufacturer" "Murata" (at 386.08 50.8 0)
      (effects (font (size 1.27 1.27) (thickness 0.15)) (justify left bottom) hide)
    )
    (property "License" "Apache-2.0" (at 388.62 50.8 0)
      (effects (font (size 1.27 1.27) (thickness 0.15)) (justify left bottom) hide)
    )
    (property "Val" "22u" (at 370.84 69.215 90)
      (effects (font (size 1.27 1.27) (thickness 0.15)) (justify left bottom))
    )
    (property "Voltage" "" (at 393.7 50.8 0)
      (effects (font (size 1.27 1.27)) (justify left bottom) hide)
    )
    (property "Dielectric" "" (at 396.24 50.8 0)
      (effects (font (size 1.27 1.27)) (justify left bottom) hide)
    )
    (property "Author" "Antmicro" (at 391.16 50.8 0)
      (effects (font (size 1.27 1.27) (thickness 0.15)) (justify left bottom) hide)
    )
    (pin "1")
    (pin "2")
    (instances
      (project "thunderbolt-pcie-adapter"
        (path ""
          (reference "C47") (unit 1)
        )
      )
    )
  )

  (symbol (lib_id "antmicropower:GND") (at 119.38 254 0) (unit 1)
    (in_bom yes) (on_board yes) (dnp no)
    (property "Reference" "#PWR0173" (at 119.38 260.35 0)
      (effects (font (size 1.27 1.27)) hide)
    )
    (property "Value" "GND" (at 117.475 258.445 0)
      (effects (font (size 1.27 1.27) (thickness 0.15)) (justify left bottom))
    )
    (property "Footprint" "" (at 119.38 254 0)
      (effects (font (size 1.27 1.27) (thickness 0.15)) (justify left bottom) hide)
    )
    (property "Datasheet" "" (at 119.38 254 0)
      (effects (font (size 1.27 1.27) (thickness 0.15)) (justify left bottom) hide)
    )
    (property "Author" "Antmicro" (at 128.27 261.62 0)
      (effects (font (size 1.27 1.27) (thickness 0.15)) (justify left bottom) hide)
    )
    (property "License" "Apache-2.0" (at 128.27 264.16 0)
      (effects (font (size 1.27 1.27) (thickness 0.15)) (justify left bottom) hide)
    )
    (pin "1")
    (instances
      (project "thunderbolt-pcie-adapter"
        (path ""
          (reference "#PWR0173") (unit 1)
        )
      )
    )
  )

  (symbol (lib_id "antmicropower:GND") (at 60.96 252.73 0) (unit 1)
    (in_bom yes) (on_board yes) (dnp no)
    (property "Reference" "#PWR0153" (at 60.96 259.08 0)
      (effects (font (size 1.27 1.27)) hide)
    )
    (property "Value" "GND" (at 59.055 257.175 0)
      (effects (font (size 1.27 1.27) (thickness 0.15)) (justify left bottom))
    )
    (property "Footprint" "" (at 60.96 252.73 0)
      (effects (font (size 1.27 1.27) (thickness 0.15)) (justify left bottom) hide)
    )
    (property "Datasheet" "" (at 60.96 252.73 0)
      (effects (font (size 1.27 1.27) (thickness 0.15)) (justify left bottom) hide)
    )
    (property "Author" "Antmicro" (at 69.85 260.35 0)
      (effects (font (size 1.27 1.27) (thickness 0.15)) (justify left bottom) hide)
    )
    (property "License" "Apache-2.0" (at 69.85 262.89 0)
      (effects (font (size 1.27 1.27) (thickness 0.15)) (justify left bottom) hide)
    )
    (pin "1")
    (instances
      (project "thunderbolt-pcie-adapter"
        (path ""
          (reference "#PWR0153") (unit 1)
        )
      )
    )
  )

  (symbol (lib_id "antmicropower:PWR_FLAG") (at 166.37 214.63 180) (unit 1)
    (in_bom yes) (on_board yes) (dnp no)
    (property "Reference" "#FLG03" (at 166.37 216.535 0)
      (effects (font (size 1.27 1.27)) hide)
    )
    (property "Value" "PWR_FLAG" (at 166.37 218.44 0)
      (effects (font (size 1.27 1.27)))
    )
    (property "Footprint" "" (at 166.37 214.63 0)
      (effects (font (size 1.27 1.27)) hide)
    )
    (property "Datasheet" "" (at 166.37 214.63 0)
      (effects (font (size 1.27 1.27)) hide)
    )
    (pin "1")
    (instances
      (project "thunderbolt-pcie-adapter"
        (path ""
          (reference "#FLG03") (unit 1)
        )
      )
    )
  )

  (symbol (lib_id "antmicropower:PWR_FLAG") (at 374.65 146.05 0) (unit 1)
    (in_bom yes) (on_board yes) (dnp no)
    (property "Reference" "#FLG0111" (at 374.65 144.145 0)
      (effects (font (size 1.27 1.27)) hide)
    )
    (property "Value" "PWR_FLAG" (at 374.65 142.24 0)
      (effects (font (size 1.27 1.27)))
    )
    (property "Footprint" "" (at 374.65 146.05 0)
      (effects (font (size 1.27 1.27)) hide)
    )
    (property "Datasheet" "" (at 374.65 146.05 0)
      (effects (font (size 1.27 1.27)) hide)
    )
    (pin "1")
    (instances
      (project "thunderbolt-pcie-adapter"
        (path ""
          (reference "#FLG0111") (unit 1)
        )
      )
    )
  )

  (symbol (lib_id "antmicroCapacitorsmisc:C_22u_1206_35V") (at 63.5 213.36 90) (unit 1)
    (in_bom yes) (on_board yes) (dnp no) (fields_autoplaced)
    (property "Reference" "C10" (at 66.04 209.5436 90)
      (effects (font (size 1.27 1.27) (thickness 0.15)) (justify right))
    )
    (property "Value" "C_22u_1206_35V" (at 73.66 193.04 0)
      (effects (font (size 1.27 1.27) (thickness 0.15)) (justify left bottom) hide)
    )
    (property "Footprint" "antmicro-footprints:C_1206_3216Metric" (at 76.2 193.04 0)
      (effects (font (size 1.27 1.27) (thickness 0.15)) (justify left bottom) hide)
    )
    (property "Datasheet" "https://product.tdk.com/en/search/capacitor/ceramic/mlcc/info?part_no=3216X5R1V226M160AC" (at 78.74 193.04 0)
      (effects (font (size 1.27 1.27) (thickness 0.15)) (justify left bottom) hide)
    )
    (property "MPN" "3216X5R1V226M160AC" (at 81.28 193.04 0)
      (effects (font (size 1.27 1.27) (thickness 0.15)) (justify left bottom) hide)
    )
    (property "Manufacturer" "TDK" (at 83.82 193.04 0)
      (effects (font (size 1.27 1.27) (thickness 0.15)) (justify left bottom) hide)
    )
    (property "License" "Apache-2.0" (at 86.36 193.04 0)
      (effects (font (size 1.27 1.27) (thickness 0.15)) (justify left bottom) hide)
    )
    (property "Val" "22u" (at 66.04 212.0836 90)
      (effects (font (size 1.27 1.27) (thickness 0.15)) (justify right))
    )
    (property "Voltage" "35V" (at 91.44 193.04 0)
      (effects (font (size 1.27 1.27)) (justify left bottom) hide)
    )
    (property "Dielectric" "" (at 93.98 193.04 0)
      (effects (font (size 1.27 1.27)) (justify left bottom) hide)
    )
    (property "Author" "Antmicro" (at 88.9 193.04 0)
      (effects (font (size 1.27 1.27) (thickness 0.15)) (justify left bottom) hide)
    )
    (pin "1")
    (pin "2")
    (instances
      (project "thunderbolt-pcie-adapter"
        (path ""
          (reference "C10") (unit 1)
        )
      )
    )
  )

  (symbol (lib_id "antmicroResistors0402:R_10k_0402") (at 160.02 132.08 90) (unit 1)
    (in_bom yes) (on_board yes) (dnp no)
    (property "Reference" "R39" (at 161.29 128.27 90)
      (effects (font (size 1.27 1.27) (thickness 0.15)) (justify right))
    )
    (property "Value" "R_10k_0402" (at 172.72 111.76 0)
      (effects (font (size 1.27 1.27) (thickness 0.15)) (justify left bottom) hide)
    )
    (property "Footprint" "antmicro-footprints:R_0402_1005Metric" (at 175.26 111.76 0)
      (effects (font (size 1.27 1.27) (thickness 0.15)) (justify left bottom) hide)
    )
    (property "Datasheet" "https://www.bourns.com/docs/product-datasheets/cr.pdf" (at 177.8 111.76 0)
      (effects (font (size 1.27 1.27) (thickness 0.15)) (justify left bottom) hide)
    )
    (property "MPN" "CR0402-FX-1002GLF" (at 180.34 111.76 0)
      (effects (font (size 1.27 1.27) (thickness 0.15)) (justify left bottom) hide)
    )
    (property "Manufacturer" "Bourns" (at 182.88 111.76 0)
      (effects (font (size 1.27 1.27) (thickness 0.15)) (justify left bottom) hide)
    )
    (property "License" "Apache-2.0" (at 185.42 111.76 0)
      (effects (font (size 1.27 1.27) (thickness 0.15)) (justify left bottom) hide)
    )
    (property "Val" "10k" (at 165.1 129.54 90)
      (effects (font (size 1.27 1.27) (thickness 0.15)) (justify left bottom))
    )
    (property "Tolerance" "1%" (at 170.18 111.76 0)
      (effects (font (size 1.27 1.27)) (justify left bottom) hide)
    )
    (property "Author" "Antmicro" (at 187.96 111.76 0)
      (effects (font (size 1.27 1.27) (thickness 0.15)) (justify left bottom) hide)
    )
    (pin "1")
    (pin "2")
    (instances
      (project "thunderbolt-pcie-adapter"
        (path ""
          (reference "R39") (unit 1)
        )
      )
    )
  )

  (symbol (lib_id "antmicroDCDCConverters:LT8350RV") (at 138.43 212.09 0) (unit 1)
    (in_bom yes) (on_board yes) (dnp no) (fields_autoplaced)
    (property "Reference" "U1" (at 151.13 204.47 0)
      (effects (font (size 1.27 1.27)))
    )
    (property "Value" "LT8350RV" (at 195.58 222.25 0)
      (effects (font (size 1.27 1.27) (thickness 0.15)) (justify left bottom) hide)
    )
    (property "Footprint" "antmicro-footprints:QFN-32-4EP_4x6mm_P0.5mm" (at 195.58 224.79 0)
      (effects (font (size 1.27 1.27) (thickness 0.15)) (justify left bottom) hide)
    )
    (property "Datasheet" "https://www.analog.com/media/en/technical-documentation/data-sheets/lt8350.pdf" (at 195.58 227.33 0)
      (effects (font (size 1.27 1.27) (thickness 0.15)) (justify left bottom) hide)
    )
    (property "MPN" "LT8350RV#PBF" (at 151.13 207.01 0)
      (effects (font (size 1.27 1.27) (thickness 0.15)))
    )
    (property "Manufacturer" "Analog Devices" (at 195.58 229.87 0)
      (effects (font (size 1.27 1.27) (thickness 0.15)) (justify left bottom) hide)
    )
    (property "License" "Apache-2.0" (at 195.58 232.41 0)
      (effects (font (size 1.27 1.27) (thickness 0.15)) (justify left bottom) hide)
    )
    (property "Author" "Antmicro" (at 195.58 234.95 0)
      (effects (font (size 1.27 1.27) (thickness 0.15)) (justify left bottom) hide)
    )
    (pin "10")
    (pin "11")
    (pin "12")
    (pin "13")
    (pin "14")
    (pin "15")
    (pin "16")
    (pin "17")
    (pin "18")
    (pin "19")
    (pin "2")
    (pin "20")
    (pin "21")
    (pin "22")
    (pin "24")
    (pin "25")
    (pin "27")
    (pin "28")
    (pin "29")
    (pin "3")
    (pin "30")
    (pin "31")
    (pin "32")
    (pin "33")
    (pin "34")
    (pin "35")
    (pin "36")
    (pin "5")
    (pin "6")
    (pin "7")
    (pin "8")
    (pin "9")
    (pin "MP")
    (instances
      (project "thunderbolt-pcie-adapter"
        (path ""
          (reference "U1") (unit 1)
        )
      )
    )
  )

  (symbol (lib_id "antmicroResistors0402:R_100k_0402") (at 50.8 152.4 0) (unit 1)
    (in_bom yes) (on_board yes) (dnp no)
    (property "Reference" "R10" (at 53.34 154.305 0)
      (effects (font (size 1.27 1.27) (thickness 0.15)))
    )
    (property "Value" "R_100k_0402" (at 71.12 165.1 0)
      (effects (font (size 1.27 1.27) (thickness 0.15)) (justify left bottom) hide)
    )
    (property "Footprint" "antmicro-footprints:R_0402_1005Metric" (at 71.12 167.64 0)
      (effects (font (size 1.27 1.27) (thickness 0.15)) (justify left bottom) hide)
    )
    (property "Datasheet" "https://www.bourns.com/docs/product-datasheets/cr.pdf" (at 71.12 170.18 0)
      (effects (font (size 1.27 1.27) (thickness 0.15)) (justify left bottom) hide)
    )
    (property "MPN" "CR0402-FX-1003GLF" (at 71.12 172.72 0)
      (effects (font (size 1.27 1.27) (thickness 0.15)) (justify left bottom) hide)
    )
    (property "Manufacturer" "Bourns" (at 71.12 175.26 0)
      (effects (font (size 1.27 1.27) (thickness 0.15)) (justify left bottom) hide)
    )
    (property "License" "Apache-2.0" (at 71.12 177.8 0)
      (effects (font (size 1.27 1.27) (thickness 0.15)) (justify left bottom) hide)
    )
    (property "Val" "100k" (at 55.245 154.94 0)
      (effects (font (size 1.27 1.27) (thickness 0.15)) (justify left bottom))
    )
    (property "Tolerance" "1%" (at 71.12 162.56 0)
      (effects (font (size 1.27 1.27)) (justify left bottom) hide)
    )
    (property "Author" "Antmicro" (at 71.12 180.34 0)
      (effects (font (size 1.27 1.27) (thickness 0.15)) (justify left bottom) hide)
    )
    (pin "1")
    (pin "2")
    (instances
      (project "thunderbolt-pcie-adapter"
        (path ""
          (reference "R10") (unit 1)
        )
      )
    )
  )

  (symbol (lib_id "antmicroCapacitors0402:C_100n_0402") (at 170.18 237.49 0) (unit 1)
    (in_bom yes) (on_board yes) (dnp no)
    (property "Reference" "C26" (at 177.165 236.22 0)
      (effects (font (size 1.27 1.27) (thickness 0.15)) (justify right))
    )
    (property "Value" "C_100n_0402" (at 190.5 247.65 0)
      (effects (font (size 1.27 1.27) (thickness 0.15)) (justify left bottom) hide)
    )
    (property "Footprint" "antmicro-footprints:C_0402_1005Metric" (at 190.5 250.19 0)
      (effects (font (size 1.27 1.27) (thickness 0.15)) (justify left bottom) hide)
    )
    (property "Datasheet" "https://www.murata.com/products/productdetail?partno=GRM155R61H104KE14%23" (at 190.5 252.73 0)
      (effects (font (size 1.27 1.27) (thickness 0.15)) (justify left bottom) hide)
    )
    (property "MPN" "GRM155R61H104KE14D" (at 190.5 255.27 0)
      (effects (font (size 1.27 1.27) (thickness 0.15)) (justify left bottom) hide)
    )
    (property "Manufacturer" "Murata" (at 190.5 257.81 0)
      (effects (font (size 1.27 1.27) (thickness 0.15)) (justify left bottom) hide)
    )
    (property "License" "Apache-2.0" (at 190.5 260.35 0)
      (effects (font (size 1.27 1.27) (thickness 0.15)) (justify left bottom) hide)
    )
    (property "Val" "100n" (at 167.005 236.855 0)
      (effects (font (size 1.27 1.27) (thickness 0.15)) (justify left bottom))
    )
    (property "Voltage" "50V" (at 190.5 265.43 0)
      (effects (font (size 1.27 1.27)) (justify left bottom) hide)
    )
    (property "Dielectric" "X5R" (at 190.5 267.97 0)
      (effects (font (size 1.27 1.27)) (justify left bottom) hide)
    )
    (property "Author" "Antmicro" (at 190.5 262.89 0)
      (effects (font (size 1.27 1.27) (thickness 0.15)) (justify left bottom) hide)
    )
    (pin "1")
    (pin "2")
    (instances
      (project "thunderbolt-pcie-adapter"
        (path ""
          (reference "C26") (unit 1)
        )
      )
    )
  )

  (symbol (lib_id "antmicroFerriteBeadsandChips:FB_30Z_8.5A_Murata-BLM21SN_0805") (at 43.18 207.01 0) (mirror x) (unit 1)
    (in_bom yes) (on_board yes) (dnp no)
    (property "Reference" "FB1" (at 45.6819 213.36 0)
      (effects (font (size 1.27 1.27) (thickness 0.15)))
    )
    (property "Value" "FB_30Z_8.5A_Murata-BLM21SN_0805" (at 57.15 204.47 0)
      (effects (font (size 1.27 1.27) (thickness 0.15)) (justify left bottom) hide)
    )
    (property "Footprint" "antmicro-footprints:FB_0805_2012Metric" (at 57.15 199.39 0)
      (effects (font (size 1.27 1.27) (thickness 0.15)) (justify left bottom) hide)
    )
    (property "Datasheet" "https://www.murata.com/en-sg/products/productdata/8796738977822/ENFA0005.pdf?1519270210000" (at 57.15 196.85 0)
      (effects (font (size 1.27 1.27) (thickness 0.15)) (justify left bottom) hide)
    )
    (property "MPN" "BLM21SN300SZ1D" (at 57.15 194.31 0)
      (effects (font (size 1.27 1.27) (thickness 0.15)) (justify left bottom) hide)
    )
    (property "Manufacturer" "Murata" (at 57.15 191.77 0)
      (effects (font (size 1.27 1.27) (thickness 0.15)) (justify left bottom) hide)
    )
    (property "License" "Apache-2.0" (at 57.15 186.69 0)
      (effects (font (size 1.27 1.27) (thickness 0.15)) (justify left bottom) hide)
    )
    (property "Author" "Antmicro" (at 57.15 189.23 0)
      (effects (font (size 1.27 1.27) (thickness 0.15)) (justify left bottom) hide)
    )
    (property "Val" "30Z/8.5A" (at 45.6819 210.82 0)
      (effects (font (size 1.27 1.27)))
    )
    (property "Current" "" (at 63.5 184.15 0)
      (effects (font (size 1.27 1.27) (thickness 0.15)) (justify left bottom) hide)
    )
    (pin "1")
    (pin "2")
    (instances
      (project "thunderbolt-pcie-adapter"
        (path ""
          (reference "FB1") (unit 1)
        )
      )
    )
  )

  (symbol (lib_id "antmicropower:GND") (at 259.08 171.45 0) (unit 1)
    (in_bom yes) (on_board yes) (dnp no)
    (property "Reference" "#PWR0155" (at 259.08 177.8 0)
      (effects (font (size 1.27 1.27)) hide)
    )
    (property "Value" "GND" (at 257.175 175.895 0)
      (effects (font (size 1.27 1.27) (thickness 0.15)) (justify left bottom))
    )
    (property "Footprint" "" (at 259.08 171.45 0)
      (effects (font (size 1.27 1.27) (thickness 0.15)) (justify left bottom) hide)
    )
    (property "Datasheet" "" (at 259.08 171.45 0)
      (effects (font (size 1.27 1.27) (thickness 0.15)) (justify left bottom) hide)
    )
    (property "Author" "Antmicro" (at 267.97 179.07 0)
      (effects (font (size 1.27 1.27) (thickness 0.15)) (justify left bottom) hide)
    )
    (property "License" "Apache-2.0" (at 267.97 181.61 0)
      (effects (font (size 1.27 1.27) (thickness 0.15)) (justify left bottom) hide)
    )
    (pin "1")
    (instances
      (project "thunderbolt-pcie-adapter"
        (path ""
          (reference "#PWR0155") (unit 1)
        )
      )
    )
  )

  (symbol (lib_id "antmicropower:GND") (at 83.82 215.9 0) (unit 1)
    (in_bom yes) (on_board yes) (dnp no)
    (property "Reference" "#PWR0168" (at 83.82 222.25 0)
      (effects (font (size 1.27 1.27)) hide)
    )
    (property "Value" "GND" (at 81.915 220.345 0)
      (effects (font (size 1.27 1.27) (thickness 0.15)) (justify left bottom))
    )
    (property "Footprint" "" (at 83.82 215.9 0)
      (effects (font (size 1.27 1.27) (thickness 0.15)) (justify left bottom) hide)
    )
    (property "Datasheet" "" (at 83.82 215.9 0)
      (effects (font (size 1.27 1.27) (thickness 0.15)) (justify left bottom) hide)
    )
    (property "Author" "Antmicro" (at 92.71 223.52 0)
      (effects (font (size 1.27 1.27) (thickness 0.15)) (justify left bottom) hide)
    )
    (property "License" "Apache-2.0" (at 92.71 226.06 0)
      (effects (font (size 1.27 1.27) (thickness 0.15)) (justify left bottom) hide)
    )
    (pin "1")
    (instances
      (project "thunderbolt-pcie-adapter"
        (path ""
          (reference "#PWR0168") (unit 1)
        )
      )
    )
  )

  (symbol (lib_id "antmicroCapacitors0402:C_4u7_25V_0402") (at 64.77 35.56 90) (unit 1)
    (in_bom yes) (on_board yes) (dnp yes)
    (property "Reference" "C20" (at 66.675 31.75 90)
      (effects (font (size 1.27 1.27) (thickness 0.15)) (justify right))
    )
    (property "Value" "C_4u7_25V_0402" (at 74.93 15.24 0)
      (effects (font (size 1.27 1.27) (thickness 0.15)) (justify left bottom) hide)
    )
    (property "Footprint" "antmicro-footprints:C_0402_1005Metric" (at 77.47 15.24 0)
      (effects (font (size 1.27 1.27) (thickness 0.15)) (justify left bottom) hide)
    )
    (property "Datasheet" "https://www.murata.com/products/productdetail?partno=GRM155C61E475ME15%23" (at 80.01 15.24 0)
      (effects (font (size 1.27 1.27) (thickness 0.15)) (justify left bottom) hide)
    )
    (property "MPN" "GRM155C61E475ME15J" (at 82.55 15.24 0)
      (effects (font (size 1.27 1.27) (thickness 0.15)) (justify left bottom) hide)
    )
    (property "Manufacturer" "Murata" (at 85.09 15.24 0)
      (effects (font (size 1.27 1.27) (thickness 0.15)) (justify left bottom) hide)
    )
    (property "License" "Apache-2.0" (at 87.63 15.24 0)
      (effects (font (size 1.27 1.27) (thickness 0.15)) (justify left bottom) hide)
    )
    (property "Val" "4u7" (at 66.675 34.29 90)
      (effects (font (size 1.27 1.27) (thickness 0.15)) (justify right))
    )
    (property "Voltage" "25V" (at 67.31 34.2835 90)
      (effects (font (size 1.27 1.27)) (justify right) hide)
    )
    (property "Dielectric" "X5S" (at 95.25 15.24 0)
      (effects (font (size 1.27 1.27)) (justify left bottom) hide)
    )
    (property "Author" "Antmicro" (at 90.17 15.24 0)
      (effects (font (size 1.27 1.27) (thickness 0.15)) (justify left bottom) hide)
    )
    (pin "1")
    (pin "2")
    (instances
      (project "thunderbolt-pcie-adapter"
        (path ""
          (reference "C20") (unit 1)
        )
      )
    )
  )

  (symbol (lib_id "antmicroCapacitorsmisc:C_10u_0805_35V") (at 83.82 213.36 270) (mirror x) (unit 1)
    (in_bom yes) (on_board yes) (dnp no) (fields_autoplaced)
    (property "Reference" "C12" (at 86.36 209.5436 90)
      (effects (font (size 1.27 1.27) (thickness 0.15)) (justify left))
    )
    (property "Value" "C_10u_0805_35V" (at 73.66 193.04 0)
      (effects (font (size 1.27 1.27) (thickness 0.15)) (justify left bottom) hide)
    )
    (property "Footprint" "antmicro-footprints:C_0805_2012Metric" (at 71.12 193.04 0)
      (effects (font (size 1.27 1.27) (thickness 0.15)) (justify left bottom) hide)
    )
    (property "Datasheet" "https://www.murata.com/products/productdetail?partno=GRM21BR6YA106KE43%23" (at 68.58 193.04 0)
      (effects (font (size 1.27 1.27) (thickness 0.15)) (justify left bottom) hide)
    )
    (property "MPN" "GRM21BR6YA106KE43L" (at 66.04 193.04 0)
      (effects (font (size 1.27 1.27) (thickness 0.15)) (justify left bottom) hide)
    )
    (property "Manufacturer" "Murata" (at 63.5 193.04 0)
      (effects (font (size 1.27 1.27) (thickness 0.15)) (justify left bottom) hide)
    )
    (property "License" "Apache-2.0" (at 60.96 193.04 0)
      (effects (font (size 1.27 1.27) (thickness 0.15)) (justify left bottom) hide)
    )
    (property "Val" "10u" (at 86.36 212.0836 90)
      (effects (font (size 1.27 1.27) (thickness 0.15)) (justify left))
    )
    (property "Voltage" "35V" (at 55.88 193.04 0)
      (effects (font (size 1.27 1.27)) (justify left bottom) hide)
    )
    (property "Dielectric" "" (at 53.34 193.04 0)
      (effects (font (size 1.27 1.27)) (justify left bottom) hide)
    )
    (property "Author" "Antmicro" (at 58.42 193.04 0)
      (effects (font (size 1.27 1.27) (thickness 0.15)) (justify left bottom) hide)
    )
    (pin "1")
    (pin "2")
    (instances
      (project "thunderbolt-pcie-adapter"
        (path ""
          (reference "C12") (unit 1)
        )
      )
    )
  )

  (symbol (lib_id "antmicroResistors0402:R_100k_0402") (at 60.96 251.46 90) (unit 1)
    (in_bom yes) (on_board yes) (dnp no)
    (property "Reference" "R92" (at 62.23 247.65 90)
      (effects (font (size 1.27 1.27) (thickness 0.15)) (justify right))
    )
    (property "Value" "R_100k_0402" (at 73.66 231.14 0)
      (effects (font (size 1.27 1.27) (thickness 0.15)) (justify left bottom) hide)
    )
    (property "Footprint" "antmicro-footprints:R_0402_1005Metric" (at 76.2 231.14 0)
      (effects (font (size 1.27 1.27) (thickness 0.15)) (justify left bottom) hide)
    )
    (property "Datasheet" "https://www.bourns.com/docs/product-datasheets/cr.pdf" (at 78.74 231.14 0)
      (effects (font (size 1.27 1.27) (thickness 0.15)) (justify left bottom) hide)
    )
    (property "MPN" "CR0402-FX-1003GLF" (at 81.28 231.14 0)
      (effects (font (size 1.27 1.27) (thickness 0.15)) (justify left bottom) hide)
    )
    (property "Manufacturer" "Bourns" (at 83.82 231.14 0)
      (effects (font (size 1.27 1.27) (thickness 0.15)) (justify left bottom) hide)
    )
    (property "License" "Apache-2.0" (at 86.36 231.14 0)
      (effects (font (size 1.27 1.27) (thickness 0.15)) (justify left bottom) hide)
    )
    (property "Val" "100k" (at 67.31 248.92 90)
      (effects (font (size 1.27 1.27) (thickness 0.15)) (justify left bottom))
    )
    (property "Tolerance" "1%" (at 71.12 231.14 0)
      (effects (font (size 1.27 1.27)) (justify left bottom) hide)
    )
    (property "Author" "Antmicro" (at 88.9 231.14 0)
      (effects (font (size 1.27 1.27) (thickness 0.15)) (justify left bottom) hide)
    )
    (pin "1")
    (pin "2")
    (instances
      (project "thunderbolt-pcie-adapter"
        (path ""
          (reference "R92") (unit 1)
        )
      )
    )
  )

  (symbol (lib_id "antmicroResistors0402:R_10k_0402") (at 66.04 106.68 0) (unit 1)
    (in_bom yes) (on_board yes) (dnp no)
    (property "Reference" "R20" (at 68.58 108.585 0)
      (effects (font (size 1.27 1.27) (thickness 0.15)))
    )
    (property "Value" "R_10k_0402" (at 86.36 119.38 0)
      (effects (font (size 1.27 1.27) (thickness 0.15)) (justify left bottom) hide)
    )
    (property "Footprint" "antmicro-footprints:R_0402_1005Metric" (at 86.36 121.92 0)
      (effects (font (size 1.27 1.27) (thickness 0.15)) (justify left bottom) hide)
    )
    (property "Datasheet" "https://www.bourns.com/docs/product-datasheets/cr.pdf" (at 86.36 124.46 0)
      (effects (font (size 1.27 1.27) (thickness 0.15)) (justify left bottom) hide)
    )
    (property "MPN" "CR0402-FX-1002GLF" (at 86.36 127 0)
      (effects (font (size 1.27 1.27) (thickness 0.15)) (justify left bottom) hide)
    )
    (property "Manufacturer" "Bourns" (at 86.36 129.54 0)
      (effects (font (size 1.27 1.27) (thickness 0.15)) (justify left bottom) hide)
    )
    (property "License" "Apache-2.0" (at 86.36 132.08 0)
      (effects (font (size 1.27 1.27) (thickness 0.15)) (justify left bottom) hide)
    )
    (property "Val" "10k" (at 71.12 106.045 0)
      (effects (font (size 1.27 1.27) (thickness 0.15)) (justify left bottom))
    )
    (property "Tolerance" "1%" (at 86.36 116.84 0)
      (effects (font (size 1.27 1.27)) (justify left bottom) hide)
    )
    (property "Author" "Antmicro" (at 86.36 134.62 0)
      (effects (font (size 1.27 1.27) (thickness 0.15)) (justify left bottom) hide)
    )
    (pin "1")
    (pin "2")
    (instances
      (project "thunderbolt-pcie-adapter"
        (path ""
          (reference "R20") (unit 1)
        )
      )
    )
  )

  (symbol (lib_id "antmicroTransistorsFETsMOSFETsSingle:SI7613DN-T1-GE3") (at 358.14 153.67 90) (unit 1)
    (in_bom yes) (on_board yes) (dnp no) (fields_autoplaced)
    (property "Reference" "Q6" (at 355.6 139.7 90)
      (effects (font (size 1.524 1.524)))
    )
    (property "Value" "SI7613DN-T1-GE3" (at 355.6 138.43 0)
      (effects (font (size 1.27 1.27) (thickness 0.15)) (justify left bottom) hide)
    )
    (property "Footprint" "antmicro-footprints:Vishay_PowerPAK_1212-8_Single" (at 356.87 138.43 0)
      (effects (font (size 1.27 1.27) (thickness 0.15)) (justify left bottom) hide)
    )
    (property "Datasheet" "https://www.vishay.com/docs/64809/si7613dn.pdf" (at 359.41 138.43 0)
      (effects (font (size 1.27 1.27) (thickness 0.15)) (justify left bottom) hide)
    )
    (property "MPN" "SI7613DN-T1-GE3" (at 355.6 142.24 90)
      (effects (font (size 1.27 1.27) (thickness 0.15)))
    )
    (property "Manufacturer" "Vishay" (at 365.76 138.43 0)
      (effects (font (size 1.27 1.27) (thickness 0.15)) (justify left bottom) hide)
    )
    (property "Author" "Antmicro" (at 368.3 138.43 0)
      (effects (font (size 1.27 1.27) (thickness 0.15)) (justify left bottom) hide)
    )
    (property "License" "Apache-2.0" (at 370.84 138.43 0)
      (effects (font (size 1.27 1.27) (thickness 0.15)) (justify left bottom) hide)
    )
    (pin "1")
    (pin "2")
    (pin "3")
    (pin "4")
    (pin "5")
    (instances
      (project "thunderbolt-pcie-adapter"
        (path ""
          (reference "Q6") (unit 1)
        )
      )
    )
  )

  (symbol (lib_id "antmicropower:GND") (at 270.51 224.79 0) (unit 1)
    (in_bom yes) (on_board yes) (dnp no)
    (property "Reference" "#PWR0185" (at 270.51 231.14 0)
      (effects (font (size 1.27 1.27)) hide)
    )
    (property "Value" "GND" (at 268.605 229.235 0)
      (effects (font (size 1.27 1.27) (thickness 0.15)) (justify left bottom))
    )
    (property "Footprint" "" (at 270.51 224.79 0)
      (effects (font (size 1.27 1.27) (thickness 0.15)) (justify left bottom) hide)
    )
    (property "Datasheet" "" (at 270.51 224.79 0)
      (effects (font (size 1.27 1.27) (thickness 0.15)) (justify left bottom) hide)
    )
    (property "Author" "Antmicro" (at 279.4 232.41 0)
      (effects (font (size 1.27 1.27) (thickness 0.15)) (justify left bottom) hide)
    )
    (property "License" "Apache-2.0" (at 279.4 234.95 0)
      (effects (font (size 1.27 1.27) (thickness 0.15)) (justify left bottom) hide)
    )
    (pin "1")
    (instances
      (project "thunderbolt-pcie-adapter"
        (path ""
          (reference "#PWR0185") (unit 1)
        )
      )
    )
  )

  (symbol (lib_id "antmicropower:GND") (at 176.53 85.09 0) (unit 1)
    (in_bom yes) (on_board yes) (dnp no)
    (property "Reference" "#PWR0160" (at 176.53 91.44 0)
      (effects (font (size 1.27 1.27)) hide)
    )
    (property "Value" "GND" (at 174.625 89.535 0)
      (effects (font (size 1.27 1.27) (thickness 0.15)) (justify left bottom))
    )
    (property "Footprint" "" (at 176.53 85.09 0)
      (effects (font (size 1.27 1.27) (thickness 0.15)) (justify left bottom) hide)
    )
    (property "Datasheet" "" (at 176.53 85.09 0)
      (effects (font (size 1.27 1.27) (thickness 0.15)) (justify left bottom) hide)
    )
    (property "Author" "Antmicro" (at 185.42 92.71 0)
      (effects (font (size 1.27 1.27) (thickness 0.15)) (justify left bottom) hide)
    )
    (property "License" "Apache-2.0" (at 185.42 95.25 0)
      (effects (font (size 1.27 1.27) (thickness 0.15)) (justify left bottom) hide)
    )
    (pin "1")
    (instances
      (project "thunderbolt-pcie-adapter"
        (path ""
          (reference "#PWR0160") (unit 1)
        )
      )
    )
  )

  (symbol (lib_id "antmicroCapacitors0402:C_2u2_0402") (at 135.89 66.04 0) (unit 1)
    (in_bom yes) (on_board yes) (dnp no)
    (property "Reference" "C37" (at 140.97 64.77 0)
      (effects (font (size 1.27 1.27) (thickness 0.15)))
    )
    (property "Value" "C_2u2_0402" (at 156.21 76.2 0)
      (effects (font (size 1.27 1.27) (thickness 0.15)) (justify left bottom) hide)
    )
    (property "Footprint" "antmicro-footprints:C_0402_1005Metric" (at 156.21 78.74 0)
      (effects (font (size 1.27 1.27) (thickness 0.15)) (justify left bottom) hide)
    )
    (property "Datasheet" "https://product.tdk.com/en/search/capacitor/ceramic/mlcc/info?part_no=C1005X5R1A225K050BC" (at 156.21 81.28 0)
      (effects (font (size 1.27 1.27) (thickness 0.15)) (justify left bottom) hide)
    )
    (property "MPN" "C1005X5R1A225K050BC" (at 156.21 83.82 0)
      (effects (font (size 1.27 1.27) (thickness 0.15)) (justify left bottom) hide)
    )
    (property "Manufacturer" "TDK" (at 156.21 86.36 0)
      (effects (font (size 1.27 1.27) (thickness 0.15)) (justify left bottom) hide)
    )
    (property "License" "Apache-2.0" (at 156.21 88.9 0)
      (effects (font (size 1.27 1.27) (thickness 0.15)) (justify left bottom) hide)
    )
    (property "Val" "2u2" (at 139.065 67.945 0)
      (effects (font (size 1.27 1.27) (thickness 0.15)) (justify left bottom))
    )
    (property "Voltage" "" (at 156.21 93.98 0)
      (effects (font (size 1.27 1.27)) (justify left bottom) hide)
    )
    (property "Dielectric" "" (at 156.21 96.52 0)
      (effects (font (size 1.27 1.27)) (justify left bottom) hide)
    )
    (property "Author" "Antmicro" (at 156.21 91.44 0)
      (effects (font (size 1.27 1.27) (thickness 0.15)) (justify left bottom) hide)
    )
    (pin "1")
    (pin "2")
    (instances
      (project "thunderbolt-pcie-adapter"
        (path ""
          (reference "C37") (unit 1)
        )
      )
    )
  )

  (symbol (lib_id "antmicroTestPoints:TP_0.75mm_SMD") (at 134.62 237.49 0) (mirror y) (unit 1)
    (in_bom no) (on_board yes) (dnp no)
    (property "Reference" "TP4" (at 130.81 237.49 0)
      (effects (font (size 1.27 1.27) (thickness 0.15)) (justify left))
    )
    (property "Value" "TP_0.75mm_SMD" (at 129.54 237.4899 0)
      (effects (font (size 1.27 1.27) (thickness 0.15)) (justify left bottom) hide)
    )
    (property "Footprint" "antmicro-footprints:TP_SMD_0.75mm" (at 119.38 247.65 0)
      (effects (font (size 1.27 1.27) (thickness 0.15)) (justify left bottom) hide)
    )
    (property "Datasheet" "" (at 119.38 250.19 0)
      (effects (font (size 1.27 1.27) (thickness 0.15)) (justify left bottom) hide)
    )
    (property "License" "Apache-2.0" (at 119.38 255.27 0)
      (effects (font (size 1.27 1.27) (thickness 0.15)) (justify left bottom) hide)
    )
    (property "Manufacturer" "" (at 129.54 240.0299 0)
      (effects (font (size 1.27 1.27) (thickness 0.15)) (justify left bottom) hide)
    )
    (property "MPN" "" (at 134.62 237.49 0)
      (effects (font (size 1.27 1.27) (thickness 0.15)) (justify left bottom) hide)
    )
    (property "Author" "Antmicro" (at 119.38 252.73 0)
      (effects (font (size 1.27 1.27) (thickness 0.15)) (justify left bottom) hide)
    )
    (pin "1")
    (instances
      (project "thunderbolt-pcie-adapter"
        (path ""
          (reference "TP4") (unit 1)
        )
      )
    )
  )

  (symbol (lib_id "antmicroCapacitors0402:C_10u_0402") (at 66.04 63.5 0) (unit 1)
    (in_bom yes) (on_board yes) (dnp no)
    (property "Reference" "C23" (at 64.77 62.23 0)
      (effects (font (size 1.27 1.27) (thickness 0.15)))
    )
    (property "Value" "C_10u_0402" (at 86.36 73.66 0)
      (effects (font (size 1.27 1.27) (thickness 0.15)) (justify left bottom) hide)
    )
    (property "Footprint" "antmicro-footprints:C_0402_1005Metric" (at 86.36 76.2 0)
      (effects (font (size 1.27 1.27) (thickness 0.15)) (justify left bottom) hide)
    )
    (property "Datasheet" "https://www.yageo.com/en/Chart/Download/pdf/CC0402MRX5R5BB106" (at 86.36 78.74 0)
      (effects (font (size 1.27 1.27) (thickness 0.15)) (justify left bottom) hide)
    )
    (property "MPN" "CC0402MRX5R5BB106" (at 86.36 81.28 0)
      (effects (font (size 1.27 1.27) (thickness 0.15)) (justify left bottom) hide)
    )
    (property "Manufacturer" "YAGEO" (at 86.36 83.82 0)
      (effects (font (size 1.27 1.27) (thickness 0.15)) (justify left bottom) hide)
    )
    (property "License" "Apache-2.0" (at 86.36 86.36 0)
      (effects (font (size 1.27 1.27) (thickness 0.15)) (justify left bottom) hide)
    )
    (property "Val" "10u" (at 71.12 62.23 0)
      (effects (font (size 1.27 1.27) (thickness 0.15)))
    )
    (property "Voltage" "" (at 86.36 91.44 0)
      (effects (font (size 1.27 1.27)) (justify left bottom) hide)
    )
    (property "Dielectric" "" (at 86.36 93.98 0)
      (effects (font (size 1.27 1.27)) (justify left bottom) hide)
    )
    (property "Author" "Antmicro" (at 86.36 88.9 0)
      (effects (font (size 1.27 1.27) (thickness 0.15)) (justify left bottom) hide)
    )
    (pin "1")
    (pin "2")
    (instances
      (project "thunderbolt-pcie-adapter"
        (path ""
          (reference "C23") (unit 1)
        )
      )
    )
  )

  (symbol (lib_id "antmicroCapacitors0402:C_220p_0402") (at 166.37 83.82 90) (unit 1)
    (in_bom yes) (on_board yes) (dnp no)
    (property "Reference" "C45" (at 168.275 80.01 90)
      (effects (font (size 1.27 1.27) (thickness 0.15)) (justify right))
    )
    (property "Value" "C_220p_0402" (at 176.53 63.5 0)
      (effects (font (size 1.27 1.27) (thickness 0.15)) (justify left bottom) hide)
    )
    (property "Footprint" "antmicro-footprints:C_0402_1005Metric" (at 179.07 63.5 0)
      (effects (font (size 1.27 1.27) (thickness 0.15)) (justify left bottom) hide)
    )
    (property "Datasheet" "https://spicat.kyocera-avx.com/product/mlcc/chartview/04025C221JAT2A/" (at 181.61 63.5 0)
      (effects (font (size 1.27 1.27) (thickness 0.15)) (justify left bottom) hide)
    )
    (property "MPN" "04025C221JAT2A" (at 184.15 63.5 0)
      (effects (font (size 1.27 1.27) (thickness 0.15)) (justify left bottom) hide)
    )
    (property "Manufacturer" "KYOCERA AVX" (at 186.69 63.5 0)
      (effects (font (size 1.27 1.27) (thickness 0.15)) (justify left bottom) hide)
    )
    (property "License" "Apache-2.0" (at 189.23 63.5 0)
      (effects (font (size 1.27 1.27) (thickness 0.15)) (justify left bottom) hide)
    )
    (property "Val" "220p" (at 168.275 81.915 90)
      (effects (font (size 1.27 1.27) (thickness 0.15)) (justify right))
    )
    (property "Voltage" "" (at 194.31 63.5 0)
      (effects (font (size 1.27 1.27)) (justify left bottom) hide)
    )
    (property "Dielectric" "" (at 196.85 63.5 0)
      (effects (font (size 1.27 1.27)) (justify left bottom) hide)
    )
    (property "Author" "Antmicro" (at 191.77 63.5 0)
      (effects (font (size 1.27 1.27) (thickness 0.15)) (justify left bottom) hide)
    )
    (pin "1")
    (pin "2")
    (instances
      (project "thunderbolt-pcie-adapter"
        (path ""
          (reference "C45") (unit 1)
        )
      )
    )
  )

  (symbol (lib_id "antmicropower:PWR_FLAG") (at 138.43 205.74 0) (unit 1)
    (in_bom yes) (on_board yes) (dnp no)
    (property "Reference" "#FLG02" (at 138.43 203.835 0)
      (effects (font (size 1.27 1.27)) hide)
    )
    (property "Value" "PWR_FLAG" (at 138.43 201.93 0)
      (effects (font (size 1.27 1.27)))
    )
    (property "Footprint" "" (at 138.43 205.74 0)
      (effects (font (size 1.27 1.27)) hide)
    )
    (property "Datasheet" "" (at 138.43 205.74 0)
      (effects (font (size 1.27 1.27)) hide)
    )
    (pin "1")
    (instances
      (project "thunderbolt-pcie-adapter"
        (path ""
          (reference "#FLG02") (unit 1)
        )
      )
    )
  )

  (symbol (lib_id "antmicroCapacitors0402:C_100n_0402") (at 93.98 213.36 270) (mirror x) (unit 1)
    (in_bom yes) (on_board yes) (dnp no) (fields_autoplaced)
    (property "Reference" "C14" (at 96.52 209.5436 90)
      (effects (font (size 1.27 1.27) (thickness 0.15)) (justify left))
    )
    (property "Value" "C_100n_0402" (at 83.82 193.04 0)
      (effects (font (size 1.27 1.27) (thickness 0.15)) (justify left bottom) hide)
    )
    (property "Footprint" "antmicro-footprints:C_0402_1005Metric" (at 81.28 193.04 0)
      (effects (font (size 1.27 1.27) (thickness 0.15)) (justify left bottom) hide)
    )
    (property "Datasheet" "https://www.murata.com/products/productdetail?partno=GRM155R61H104KE14%23" (at 78.74 193.04 0)
      (effects (font (size 1.27 1.27) (thickness 0.15)) (justify left bottom) hide)
    )
    (property "MPN" "GRM155R61H104KE14D" (at 76.2 193.04 0)
      (effects (font (size 1.27 1.27) (thickness 0.15)) (justify left bottom) hide)
    )
    (property "Manufacturer" "Murata" (at 73.66 193.04 0)
      (effects (font (size 1.27 1.27) (thickness 0.15)) (justify left bottom) hide)
    )
    (property "License" "Apache-2.0" (at 71.12 193.04 0)
      (effects (font (size 1.27 1.27) (thickness 0.15)) (justify left bottom) hide)
    )
    (property "Val" "100n" (at 96.52 212.0836 90)
      (effects (font (size 1.27 1.27) (thickness 0.15)) (justify left))
    )
    (property "Voltage" "50V" (at 66.04 193.04 0)
      (effects (font (size 1.27 1.27)) (justify left bottom) hide)
    )
    (property "Dielectric" "X5R" (at 63.5 193.04 0)
      (effects (font (size 1.27 1.27)) (justify left bottom) hide)
    )
    (property "Author" "Antmicro" (at 68.58 193.04 0)
      (effects (font (size 1.27 1.27) (thickness 0.15)) (justify left bottom) hide)
    )
    (pin "1")
    (pin "2")
    (instances
      (project "thunderbolt-pcie-adapter"
        (path ""
          (reference "C14") (unit 1)
        )
      )
    )
  )

  (symbol (lib_id "antmicropower:GND") (at 68.58 252.73 0) (unit 1)
    (in_bom yes) (on_board yes) (dnp no)
    (property "Reference" "#PWR0152" (at 68.58 259.08 0)
      (effects (font (size 1.27 1.27)) hide)
    )
    (property "Value" "GND" (at 66.675 257.175 0)
      (effects (font (size 1.27 1.27) (thickness 0.15)) (justify left bottom))
    )
    (property "Footprint" "" (at 68.58 252.73 0)
      (effects (font (size 1.27 1.27) (thickness 0.15)) (justify left bottom) hide)
    )
    (property "Datasheet" "" (at 68.58 252.73 0)
      (effects (font (size 1.27 1.27) (thickness 0.15)) (justify left bottom) hide)
    )
    (property "Author" "Antmicro" (at 77.47 260.35 0)
      (effects (font (size 1.27 1.27) (thickness 0.15)) (justify left bottom) hide)
    )
    (property "License" "Apache-2.0" (at 77.47 262.89 0)
      (effects (font (size 1.27 1.27) (thickness 0.15)) (justify left bottom) hide)
    )
    (pin "1")
    (instances
      (project "thunderbolt-pcie-adapter"
        (path ""
          (reference "#PWR0152") (unit 1)
        )
      )
    )
  )

  (symbol (lib_id "antmicropower:GND") (at 116.84 218.44 0) (unit 1)
    (in_bom yes) (on_board yes) (dnp no)
    (property "Reference" "#PWR0171" (at 116.84 224.79 0)
      (effects (font (size 1.27 1.27)) hide)
    )
    (property "Value" "GND" (at 114.935 222.885 0)
      (effects (font (size 1.27 1.27) (thickness 0.15)) (justify left bottom))
    )
    (property "Footprint" "" (at 116.84 218.44 0)
      (effects (font (size 1.27 1.27) (thickness 0.15)) (justify left bottom) hide)
    )
    (property "Datasheet" "" (at 116.84 218.44 0)
      (effects (font (size 1.27 1.27) (thickness 0.15)) (justify left bottom) hide)
    )
    (property "Author" "Antmicro" (at 125.73 226.06 0)
      (effects (font (size 1.27 1.27) (thickness 0.15)) (justify left bottom) hide)
    )
    (property "License" "Apache-2.0" (at 125.73 228.6 0)
      (effects (font (size 1.27 1.27) (thickness 0.15)) (justify left bottom) hide)
    )
    (pin "1")
    (instances
      (project "thunderbolt-pcie-adapter"
        (path ""
          (reference "#PWR0171") (unit 1)
        )
      )
    )
  )

  (symbol (lib_id "antmicroCapacitors0402:C_10u_0402") (at 140.97 50.8 0) (unit 1)
    (in_bom yes) (on_board yes) (dnp no)
    (property "Reference" "C39" (at 146.05 49.53 0)
      (effects (font (size 1.27 1.27) (thickness 0.15)))
    )
    (property "Value" "C_10u_0402" (at 161.29 60.96 0)
      (effects (font (size 1.27 1.27) (thickness 0.15)) (justify left bottom) hide)
    )
    (property "Footprint" "antmicro-footprints:C_0402_1005Metric" (at 161.29 63.5 0)
      (effects (font (size 1.27 1.27) (thickness 0.15)) (justify left bottom) hide)
    )
    (property "Datasheet" "https://www.yageo.com/en/Chart/Download/pdf/CC0402MRX5R5BB106" (at 161.29 66.04 0)
      (effects (font (size 1.27 1.27) (thickness 0.15)) (justify left bottom) hide)
    )
    (property "MPN" "CC0402MRX5R5BB106" (at 161.29 68.58 0)
      (effects (font (size 1.27 1.27) (thickness 0.15)) (justify left bottom) hide)
    )
    (property "Manufacturer" "YAGEO" (at 161.29 71.12 0)
      (effects (font (size 1.27 1.27) (thickness 0.15)) (justify left bottom) hide)
    )
    (property "License" "Apache-2.0" (at 161.29 73.66 0)
      (effects (font (size 1.27 1.27) (thickness 0.15)) (justify left bottom) hide)
    )
    (property "Val" "10u" (at 144.145 52.705 0)
      (effects (font (size 1.27 1.27) (thickness 0.15)) (justify left bottom))
    )
    (property "Voltage" "" (at 161.29 78.74 0)
      (effects (font (size 1.27 1.27)) (justify left bottom) hide)
    )
    (property "Dielectric" "" (at 161.29 81.28 0)
      (effects (font (size 1.27 1.27)) (justify left bottom) hide)
    )
    (property "Author" "Antmicro" (at 161.29 76.2 0)
      (effects (font (size 1.27 1.27) (thickness 0.15)) (justify left bottom) hide)
    )
    (pin "1")
    (pin "2")
    (instances
      (project "thunderbolt-pcie-adapter"
        (path ""
          (reference "C39") (unit 1)
        )
      )
    )
  )

  (symbol (lib_id "antmicroResistors0402:R_10k_0402") (at 259.08 170.18 90) (unit 1)
    (in_bom yes) (on_board yes) (dnp no) (fields_autoplaced)
    (property "Reference" "R93" (at 260.985 166.37 90)
      (effects (font (size 1.27 1.27) (thickness 0.15)) (justify right))
    )
    (property "Value" "R_10k_0402" (at 271.78 149.86 0)
      (effects (font (size 1.27 1.27) (thickness 0.15)) (justify left bottom) hide)
    )
    (property "Footprint" "antmicro-footprints:R_0402_1005Metric" (at 274.32 149.86 0)
      (effects (font (size 1.27 1.27) (thickness 0.15)) (justify left bottom) hide)
    )
    (property "Datasheet" "https://www.bourns.com/docs/product-datasheets/cr.pdf" (at 276.86 149.86 0)
      (effects (font (size 1.27 1.27) (thickness 0.15)) (justify left bottom) hide)
    )
    (property "MPN" "CR0402-FX-1002GLF" (at 279.4 149.86 0)
      (effects (font (size 1.27 1.27) (thickness 0.15)) (justify left bottom) hide)
    )
    (property "Manufacturer" "Bourns" (at 281.94 149.86 0)
      (effects (font (size 1.27 1.27) (thickness 0.15)) (justify left bottom) hide)
    )
    (property "License" "Apache-2.0" (at 284.48 149.86 0)
      (effects (font (size 1.27 1.27) (thickness 0.15)) (justify left bottom) hide)
    )
    (property "Author" "Antmicro" (at 287.02 149.86 0)
      (effects (font (size 1.27 1.27) (thickness 0.15)) (justify left bottom) hide)
    )
    (property "Val" "10k" (at 260.985 168.91 90)
      (effects (font (size 1.27 1.27) (thickness 0.15)) (justify right))
    )
    (property "Tolerance" "1%" (at 269.24 149.86 0)
      (effects (font (size 1.27 1.27)) (justify left bottom) hide)
    )
    (pin "1")
    (pin "2")
    (instances
      (project "thunderbolt-pcie-adapter"
        (path ""
          (reference "R93") (unit 1)
        )
      )
    )
  )

  (symbol (lib_id "antmicroCapacitorsmisc:C_10u_0805_35V") (at 73.66 213.36 270) (mirror x) (unit 1)
    (in_bom yes) (on_board yes) (dnp no) (fields_autoplaced)
    (property "Reference" "C11" (at 76.2 209.5436 90)
      (effects (font (size 1.27 1.27) (thickness 0.15)) (justify left))
    )
    (property "Value" "C_10u_0805_35V" (at 63.5 193.04 0)
      (effects (font (size 1.27 1.27) (thickness 0.15)) (justify left bottom) hide)
    )
    (property "Footprint" "antmicro-footprints:C_0805_2012Metric" (at 60.96 193.04 0)
      (effects (font (size 1.27 1.27) (thickness 0.15)) (justify left bottom) hide)
    )
    (property "Datasheet" "https://www.murata.com/products/productdetail?partno=GRM21BR6YA106KE43%23" (at 58.42 193.04 0)
      (effects (font (size 1.27 1.27) (thickness 0.15)) (justify left bottom) hide)
    )
    (property "MPN" "GRM21BR6YA106KE43L" (at 55.88 193.04 0)
      (effects (font (size 1.27 1.27) (thickness 0.15)) (justify left bottom) hide)
    )
    (property "Manufacturer" "Murata" (at 53.34 193.04 0)
      (effects (font (size 1.27 1.27) (thickness 0.15)) (justify left bottom) hide)
    )
    (property "License" "Apache-2.0" (at 50.8 193.04 0)
      (effects (font (size 1.27 1.27) (thickness 0.15)) (justify left bottom) hide)
    )
    (property "Val" "10u" (at 76.2 212.0836 90)
      (effects (font (size 1.27 1.27) (thickness 0.15)) (justify left))
    )
    (property "Voltage" "35V" (at 45.72 193.04 0)
      (effects (font (size 1.27 1.27)) (justify left bottom) hide)
    )
    (property "Dielectric" "" (at 43.18 193.04 0)
      (effects (font (size 1.27 1.27)) (justify left bottom) hide)
    )
    (property "Author" "Antmicro" (at 48.26 193.04 0)
      (effects (font (size 1.27 1.27) (thickness 0.15)) (justify left bottom) hide)
    )
    (pin "1")
    (pin "2")
    (instances
      (project "thunderbolt-pcie-adapter"
        (path ""
          (reference "C11") (unit 1)
        )
      )
    )
  )

  (symbol (lib_id "antmicropower:GND") (at 146.05 144.78 90) (unit 1)
    (in_bom yes) (on_board yes) (dnp no)
    (property "Reference" "#PWR060" (at 152.4 144.78 0)
      (effects (font (size 1.27 1.27)) hide)
    )
    (property "Value" "GND" (at 150.495 146.685 0)
      (effects (font (size 1.27 1.27) (thickness 0.15)) (justify left bottom))
    )
    (property "Footprint" "" (at 146.05 144.78 0)
      (effects (font (size 1.27 1.27) (thickness 0.15)) (justify left bottom) hide)
    )
    (property "Datasheet" "" (at 146.05 144.78 0)
      (effects (font (size 1.27 1.27) (thickness 0.15)) (justify left bottom) hide)
    )
    (property "Author" "Antmicro" (at 153.67 135.89 0)
      (effects (font (size 1.27 1.27) (thickness 0.15)) (justify left bottom) hide)
    )
    (property "License" "Apache-2.0" (at 156.21 135.89 0)
      (effects (font (size 1.27 1.27) (thickness 0.15)) (justify left bottom) hide)
    )
    (pin "1")
    (instances
      (project "thunderbolt-pcie-adapter"
        (path ""
          (reference "#PWR060") (unit 1)
        )
      )
    )
  )

  (symbol (lib_id "antmicropower:GND") (at 339.09 171.45 0) (unit 1)
    (in_bom yes) (on_board yes) (dnp no)
    (property "Reference" "#PWR0157" (at 339.09 177.8 0)
      (effects (font (size 1.27 1.27)) hide)
    )
    (property "Value" "GND" (at 337.185 175.895 0)
      (effects (font (size 1.27 1.27) (thickness 0.15)) (justify left bottom))
    )
    (property "Footprint" "" (at 339.09 171.45 0)
      (effects (font (size 1.27 1.27) (thickness 0.15)) (justify left bottom) hide)
    )
    (property "Datasheet" "" (at 339.09 171.45 0)
      (effects (font (size 1.27 1.27) (thickness 0.15)) (justify left bottom) hide)
    )
    (property "Author" "Antmicro" (at 347.98 179.07 0)
      (effects (font (size 1.27 1.27) (thickness 0.15)) (justify left bottom) hide)
    )
    (property "License" "Apache-2.0" (at 347.98 181.61 0)
      (effects (font (size 1.27 1.27) (thickness 0.15)) (justify left bottom) hide)
    )
    (pin "1")
    (instances
      (project "thunderbolt-pcie-adapter"
        (path ""
          (reference "#PWR0157") (unit 1)
        )
      )
    )
  )

  (symbol (lib_id "antmicropower:GND") (at 62.23 58.42 0) (unit 1)
    (in_bom yes) (on_board yes) (dnp no)
    (property "Reference" "#PWR018" (at 62.23 64.77 0)
      (effects (font (size 1.27 1.27)) hide)
    )
    (property "Value" "GND" (at 55.88 60.96 0)
      (effects (font (size 1.27 1.27) (thickness 0.15)) (justify left bottom))
    )
    (property "Footprint" "" (at 62.23 58.42 0)
      (effects (font (size 1.27 1.27) (thickness 0.15)) (justify left bottom) hide)
    )
    (property "Datasheet" "" (at 62.23 58.42 0)
      (effects (font (size 1.27 1.27) (thickness 0.15)) (justify left bottom) hide)
    )
    (property "Author" "Antmicro" (at 71.12 66.04 0)
      (effects (font (size 1.27 1.27) (thickness 0.15)) (justify left bottom) hide)
    )
    (property "License" "Apache-2.0" (at 71.12 68.58 0)
      (effects (font (size 1.27 1.27) (thickness 0.15)) (justify left bottom) hide)
    )
    (pin "1")
    (instances
      (project "thunderbolt-pcie-adapter"
        (path ""
          (reference "#PWR018") (unit 1)
        )
      )
    )
  )

  (symbol (lib_id "antmicroResistors0402:R_330R_0402") (at 375.92 74.93 90) (unit 1)
    (in_bom yes) (on_board yes) (dnp no) (fields_autoplaced)
    (property "Reference" "R42" (at 377.825 71.12 90)
      (effects (font (size 1.27 1.27) (thickness 0.15)) (justify right))
    )
    (property "Value" "R_330R_0402" (at 388.62 54.61 0)
      (effects (font (size 1.27 1.27) (thickness 0.15)) (justify left bottom) hide)
    )
    (property "Footprint" "antmicro-footprints:R_0402_1005Metric" (at 391.16 54.61 0)
      (effects (font (size 1.27 1.27) (thickness 0.15)) (justify left bottom) hide)
    )
    (property "Datasheet" "https://www.bourns.com/docs/product-datasheets/cr.pdf" (at 393.7 54.61 0)
      (effects (font (size 1.27 1.27) (thickness 0.15)) (justify left bottom) hide)
    )
    (property "MPN" "CR0402-FX-3300GLF" (at 396.24 54.61 0)
      (effects (font (size 1.27 1.27) (thickness 0.15)) (justify left bottom) hide)
    )
    (property "Manufacturer" "Bourns" (at 398.78 54.61 0)
      (effects (font (size 1.27 1.27) (thickness 0.15)) (justify left bottom) hide)
    )
    (property "License" "Apache-2.0" (at 401.32 54.61 0)
      (effects (font (size 1.27 1.27) (thickness 0.15)) (justify left bottom) hide)
    )
    (property "Val" "330R" (at 377.825 73.66 90)
      (effects (font (size 1.27 1.27) (thickness 0.15)) (justify right))
    )
    (property "Tolerance" "1%" (at 386.08 54.61 0)
      (effects (font (size 1.27 1.27)) (justify left bottom) hide)
    )
    (property "Author" "Antmicro" (at 403.86 54.61 0)
      (effects (font (size 1.27 1.27) (thickness 0.15)) (justify left bottom) hide)
    )
    (pin "1")
    (pin "2")
    (instances
      (project "thunderbolt-pcie-adapter"
        (path ""
          (reference "R42") (unit 1)
        )
      )
    )
  )

  (symbol (lib_id "antmicroResistors0402:R_10k_0402") (at 52.07 242.57 0) (unit 1)
    (in_bom yes) (on_board yes) (dnp no)
    (property "Reference" "R91" (at 54.61 240.665 0)
      (effects (font (size 1.27 1.27) (thickness 0.15)))
    )
    (property "Value" "R_10k_0402" (at 72.39 255.27 0)
      (effects (font (size 1.27 1.27) (thickness 0.15)) (justify left bottom) hide)
    )
    (property "Footprint" "antmicro-footprints:R_0402_1005Metric" (at 72.39 257.81 0)
      (effects (font (size 1.27 1.27) (thickness 0.15)) (justify left bottom) hide)
    )
    (property "Datasheet" "https://www.bourns.com/docs/product-datasheets/cr.pdf" (at 72.39 260.35 0)
      (effects (font (size 1.27 1.27) (thickness 0.15)) (justify left bottom) hide)
    )
    (property "MPN" "CR0402-FX-1002GLF" (at 72.39 262.89 0)
      (effects (font (size 1.27 1.27) (thickness 0.15)) (justify left bottom) hide)
    )
    (property "Manufacturer" "Bourns" (at 72.39 265.43 0)
      (effects (font (size 1.27 1.27) (thickness 0.15)) (justify left bottom) hide)
    )
    (property "License" "Apache-2.0" (at 72.39 267.97 0)
      (effects (font (size 1.27 1.27) (thickness 0.15)) (justify left bottom) hide)
    )
    (property "Val" "10k" (at 52.705 245.11 0)
      (effects (font (size 1.27 1.27) (thickness 0.15)) (justify left bottom))
    )
    (property "Tolerance" "1%" (at 72.39 252.73 0)
      (effects (font (size 1.27 1.27)) (justify left bottom) hide)
    )
    (property "Author" "Antmicro" (at 72.39 270.51 0)
      (effects (font (size 1.27 1.27) (thickness 0.15)) (justify left bottom) hide)
    )
    (pin "1")
    (pin "2")
    (instances
      (project "thunderbolt-pcie-adapter"
        (path ""
          (reference "R91") (unit 1)
        )
      )
    )
  )

  (symbol (lib_id "antmicropower:GND") (at 146.05 154.94 90) (unit 1)
    (in_bom yes) (on_board yes) (dnp no)
    (property "Reference" "#PWR064" (at 152.4 154.94 0)
      (effects (font (size 1.27 1.27)) hide)
    )
    (property "Value" "GND" (at 150.495 156.845 0)
      (effects (font (size 1.27 1.27) (thickness 0.15)) (justify left bottom))
    )
    (property "Footprint" "" (at 146.05 154.94 0)
      (effects (font (size 1.27 1.27) (thickness 0.15)) (justify left bottom) hide)
    )
    (property "Datasheet" "" (at 146.05 154.94 0)
      (effects (font (size 1.27 1.27) (thickness 0.15)) (justify left bottom) hide)
    )
    (property "Author" "Antmicro" (at 153.67 146.05 0)
      (effects (font (size 1.27 1.27) (thickness 0.15)) (justify left bottom) hide)
    )
    (property "License" "Apache-2.0" (at 156.21 146.05 0)
      (effects (font (size 1.27 1.27) (thickness 0.15)) (justify left bottom) hide)
    )
    (pin "1")
    (instances
      (project "thunderbolt-pcie-adapter"
        (path ""
          (reference "#PWR064") (unit 1)
        )
      )
    )
  )

  (symbol (lib_id "antmicropower:GND") (at 158.75 85.09 0) (unit 1)
    (in_bom yes) (on_board yes) (dnp no)
    (property "Reference" "#PWR073" (at 158.75 91.44 0)
      (effects (font (size 1.27 1.27)) hide)
    )
    (property "Value" "GND" (at 156.845 89.535 0)
      (effects (font (size 1.27 1.27) (thickness 0.15)) (justify left bottom))
    )
    (property "Footprint" "" (at 158.75 85.09 0)
      (effects (font (size 1.27 1.27) (thickness 0.15)) (justify left bottom) hide)
    )
    (property "Datasheet" "" (at 158.75 85.09 0)
      (effects (font (size 1.27 1.27) (thickness 0.15)) (justify left bottom) hide)
    )
    (property "Author" "Antmicro" (at 167.64 92.71 0)
      (effects (font (size 1.27 1.27) (thickness 0.15)) (justify left bottom) hide)
    )
    (property "License" "Apache-2.0" (at 167.64 95.25 0)
      (effects (font (size 1.27 1.27) (thickness 0.15)) (justify left bottom) hide)
    )
    (pin "1")
    (instances
      (project "thunderbolt-pcie-adapter"
        (path ""
          (reference "#PWR073") (unit 1)
        )
      )
    )
  )

  (symbol (lib_id "antmicroCapacitors0402:C_1u_0402") (at 66.04 58.42 0) (unit 1)
    (in_bom yes) (on_board yes) (dnp no)
    (property "Reference" "C22" (at 64.77 57.15 0)
      (effects (font (size 1.27 1.27) (thickness 0.15)))
    )
    (property "Value" "C_1u_0402" (at 86.36 68.58 0)
      (effects (font (size 1.27 1.27) (thickness 0.15)) (justify left bottom) hide)
    )
    (property "Footprint" "antmicro-footprints:C_0402_1005Metric" (at 86.36 71.12 0)
      (effects (font (size 1.27 1.27) (thickness 0.15)) (justify left bottom) hide)
    )
    (property "Datasheet" "https://product.tdk.com/en/search/capacitor/ceramic/mlcc/info?part_no=C1005X6S1A105K050BC" (at 86.36 73.66 0)
      (effects (font (size 1.27 1.27) (thickness 0.15)) (justify left bottom) hide)
    )
    (property "MPN" "C1005X6S1A105K050BC" (at 86.36 76.2 0)
      (effects (font (size 1.27 1.27) (thickness 0.15)) (justify left bottom) hide)
    )
    (property "Manufacturer" "TDK" (at 86.36 78.74 0)
      (effects (font (size 1.27 1.27) (thickness 0.15)) (justify left bottom) hide)
    )
    (property "License" "Apache-2.0" (at 86.36 81.28 0)
      (effects (font (size 1.27 1.27) (thickness 0.15)) (justify left bottom) hide)
    )
    (property "Val" "1u" (at 69.85 57.15 0)
      (effects (font (size 1.27 1.27) (thickness 0.15)) (justify left bottom))
    )
    (property "Voltage" "" (at 86.36 86.36 0)
      (effects (font (size 1.27 1.27)) (justify left bottom) hide)
    )
    (property "Dielectric" "" (at 86.36 88.9 0)
      (effects (font (size 1.27 1.27)) (justify left bottom) hide)
    )
    (property "Author" "Antmicro" (at 86.36 83.82 0)
      (effects (font (size 1.27 1.27) (thickness 0.15)) (justify left bottom) hide)
    )
    (pin "1")
    (pin "2")
    (instances
      (project "thunderbolt-pcie-adapter"
        (path ""
          (reference "C22") (unit 1)
        )
      )
    )
  )

  (symbol (lib_id "antmicropower:PWR_FLAG") (at 179.07 43.18 0) (unit 1)
    (in_bom yes) (on_board yes) (dnp no)
    (property "Reference" "#FLG07" (at 179.07 41.275 0)
      (effects (font (size 1.27 1.27)) hide)
    )
    (property "Value" "PWR_FLAG" (at 179.07 39.37 0)
      (effects (font (size 1.27 1.27)))
    )
    (property "Footprint" "" (at 179.07 43.18 0)
      (effects (font (size 1.27 1.27)) hide)
    )
    (property "Datasheet" "" (at 179.07 43.18 0)
      (effects (font (size 1.27 1.27)) hide)
    )
    (pin "1")
    (instances
      (project "thunderbolt-pcie-adapter"
        (path ""
          (reference "#FLG07") (unit 1)
        )
      )
    )
  )

  (symbol (lib_id "antmicroLEDIndicationDiscrete:LED_G_0603_KP-1608CGCK") (at 375.92 67.31 90) (unit 1)
    (in_bom yes) (on_board yes) (dnp no) (fields_autoplaced)
    (property "Reference" "D2" (at 377.825 63.5 90)
      (effects (font (size 1.27 1.27) (thickness 0.15)) (justify right))
    )
    (property "Value" "LED_G_0603_KP-1608CGCK" (at 383.54 44.45 0)
      (effects (font (size 1.27 1.27) (thickness 0.15)) (justify left bottom) hide)
    )
    (property "Footprint" "antmicro-footprints:LED_0603_1608Metric_G" (at 386.08 44.45 0)
      (effects (font (size 1.27 1.27) (thickness 0.15)) (justify left bottom) hide)
    )
    (property "Datasheet" "http://www.kingbright.com/attachments/file/psearch//000/00/00/KP-1608CGCK(Ver.23B).pdf" (at 388.62 44.45 0)
      (effects (font (size 1.27 1.27) (thickness 0.15)) (justify left bottom) hide)
    )
    (property "MPN" "KP-1608CGCK" (at 391.16 44.45 0)
      (effects (font (size 1.27 1.27) (thickness 0.15)) (justify left bottom) hide)
    )
    (property "Manufacturer" "Kingbright" (at 393.7 44.45 0)
      (effects (font (size 1.27 1.27) (thickness 0.15)) (justify left bottom) hide)
    )
    (property "License" "Apache-2.0" (at 398.78 44.45 0)
      (effects (font (size 1.27 1.27) (thickness 0.15)) (justify left bottom) hide)
    )
    (property "Author" "Antmicro" (at 396.24 44.45 0)
      (effects (font (size 1.27 1.27) (thickness 0.15)) (justify left bottom) hide)
    )
    (property "Color" "Green" (at 377.825 66.04 90)
      (effects (font (size 1.27 1.27)) (justify right))
    )
    (pin "1")
    (pin "2")
    (instances
      (project "thunderbolt-pcie-adapter"
        (path ""
          (reference "D2") (unit 1)
        )
      )
    )
  )

  (symbol (lib_id "antmicropower:GND") (at 161.29 54.61 0) (unit 1)
    (in_bom yes) (on_board yes) (dnp no)
    (property "Reference" "#PWR074" (at 161.29 60.96 0)
      (effects (font (size 1.27 1.27)) hide)
    )
    (property "Value" "GND" (at 159.385 59.055 0)
      (effects (font (size 1.27 1.27) (thickness 0.15)) (justify left bottom))
    )
    (property "Footprint" "" (at 161.29 54.61 0)
      (effects (font (size 1.27 1.27) (thickness 0.15)) (justify left bottom) hide)
    )
    (property "Datasheet" "" (at 161.29 54.61 0)
      (effects (font (size 1.27 1.27) (thickness 0.15)) (justify left bottom) hide)
    )
    (property "Author" "Antmicro" (at 170.18 62.23 0)
      (effects (font (size 1.27 1.27) (thickness 0.15)) (justify left bottom) hide)
    )
    (property "License" "Apache-2.0" (at 170.18 64.77 0)
      (effects (font (size 1.27 1.27) (thickness 0.15)) (justify left bottom) hide)
    )
    (pin "1")
    (instances
      (project "thunderbolt-pcie-adapter"
        (path ""
          (reference "#PWR074") (unit 1)
        )
      )
    )
  )

  (symbol (lib_id "antmicroResistors0402:R_10k_0402") (at 66.04 88.9 0) (unit 1)
    (in_bom yes) (on_board yes) (dnp no)
    (property "Reference" "R17" (at 68.58 86.995 0)
      (effects (font (size 1.27 1.27) (thickness 0.15)))
    )
    (property "Value" "R_10k_0402" (at 86.36 101.6 0)
      (effects (font (size 1.27 1.27) (thickness 0.15)) (justify left bottom) hide)
    )
    (property "Footprint" "antmicro-footprints:R_0402_1005Metric" (at 86.36 104.14 0)
      (effects (font (size 1.27 1.27) (thickness 0.15)) (justify left bottom) hide)
    )
    (property "Datasheet" "https://www.bourns.com/docs/product-datasheets/cr.pdf" (at 86.36 106.68 0)
      (effects (font (size 1.27 1.27) (thickness 0.15)) (justify left bottom) hide)
    )
    (property "MPN" "CR0402-FX-1002GLF" (at 86.36 109.22 0)
      (effects (font (size 1.27 1.27) (thickness 0.15)) (justify left bottom) hide)
    )
    (property "Manufacturer" "Bourns" (at 86.36 111.76 0)
      (effects (font (size 1.27 1.27) (thickness 0.15)) (justify left bottom) hide)
    )
    (property "License" "Apache-2.0" (at 86.36 114.3 0)
      (effects (font (size 1.27 1.27) (thickness 0.15)) (justify left bottom) hide)
    )
    (property "Val" "10k" (at 71.12 88.265 0)
      (effects (font (size 1.27 1.27) (thickness 0.15)) (justify left bottom))
    )
    (property "Tolerance" "1%" (at 86.36 99.06 0)
      (effects (font (size 1.27 1.27)) (justify left bottom) hide)
    )
    (property "Author" "Antmicro" (at 86.36 116.84 0)
      (effects (font (size 1.27 1.27) (thickness 0.15)) (justify left bottom) hide)
    )
    (pin "1")
    (pin "2")
    (instances
      (project "thunderbolt-pcie-adapter"
        (path ""
          (reference "R17") (unit 1)
        )
      )
    )
  )

  (symbol (lib_id "antmicroResistors0402:R_12k_0402") (at 180.34 259.08 90) (unit 1)
    (in_bom yes) (on_board yes) (dnp no) (fields_autoplaced)
    (property "Reference" "R25" (at 182.88 255.27 90)
      (effects (font (size 1.27 1.27) (thickness 0.15)) (justify right))
    )
    (property "Value" "R_12k_0402" (at 193.04 238.76 0)
      (effects (font (size 1.27 1.27) (thickness 0.15)) (justify left bottom) hide)
    )
    (property "Footprint" "antmicro-footprints:R_0402_1005Metric" (at 195.58 238.76 0)
      (effects (font (size 1.27 1.27) (thickness 0.15)) (justify left bottom) hide)
    )
    (property "Datasheet" "https://www.bourns.com/docs/product-datasheets/cr.pdf" (at 198.12 238.76 0)
      (effects (font (size 1.27 1.27) (thickness 0.15)) (justify left bottom) hide)
    )
    (property "MPN" "CR0402-FX-1202GLF" (at 200.66 238.76 0)
      (effects (font (size 1.27 1.27) (thickness 0.15)) (justify left bottom) hide)
    )
    (property "Manufacturer" "Bourns" (at 203.2 238.76 0)
      (effects (font (size 1.27 1.27) (thickness 0.15)) (justify left bottom) hide)
    )
    (property "License" "Apache-2.0" (at 205.74 238.76 0)
      (effects (font (size 1.27 1.27) (thickness 0.15)) (justify left bottom) hide)
    )
    (property "Val" "12k" (at 182.88 257.81 90)
      (effects (font (size 1.27 1.27) (thickness 0.15)) (justify right))
    )
    (property "Tolerance" "1%" (at 190.5 238.76 0)
      (effects (font (size 1.27 1.27)) (justify left bottom) hide)
    )
    (property "Author" "Antmicro" (at 208.28 238.76 0)
      (effects (font (size 1.27 1.27) (thickness 0.15)) (justify left bottom) hide)
    )
    (pin "1")
    (pin "2")
    (instances
      (project "thunderbolt-pcie-adapter"
        (path ""
          (reference "R25") (unit 1)
        )
      )
    )
  )

  (symbol (lib_id "antmicroResistors0402:R_10k_0402") (at 339.09 170.18 90) (unit 1)
    (in_bom yes) (on_board yes) (dnp no) (fields_autoplaced)
    (property "Reference" "R94" (at 341.63 166.37 90)
      (effects (font (size 1.27 1.27) (thickness 0.15)) (justify right))
    )
    (property "Value" "R_10k_0402" (at 351.79 149.86 0)
      (effects (font (size 1.27 1.27) (thickness 0.15)) (justify left bottom) hide)
    )
    (property "Footprint" "antmicro-footprints:R_0402_1005Metric" (at 354.33 149.86 0)
      (effects (font (size 1.27 1.27) (thickness 0.15)) (justify left bottom) hide)
    )
    (property "Datasheet" "https://www.bourns.com/docs/product-datasheets/cr.pdf" (at 356.87 149.86 0)
      (effects (font (size 1.27 1.27) (thickness 0.15)) (justify left bottom) hide)
    )
    (property "MPN" "CR0402-FX-1002GLF" (at 359.41 149.86 0)
      (effects (font (size 1.27 1.27) (thickness 0.15)) (justify left bottom) hide)
    )
    (property "Manufacturer" "Bourns" (at 361.95 149.86 0)
      (effects (font (size 1.27 1.27) (thickness 0.15)) (justify left bottom) hide)
    )
    (property "License" "Apache-2.0" (at 364.49 149.86 0)
      (effects (font (size 1.27 1.27) (thickness 0.15)) (justify left bottom) hide)
    )
    (property "Author" "Antmicro" (at 367.03 149.86 0)
      (effects (font (size 1.27 1.27) (thickness 0.15)) (justify left bottom) hide)
    )
    (property "Val" "10k" (at 341.63 168.91 90)
      (effects (font (size 1.27 1.27) (thickness 0.15)) (justify right))
    )
    (property "Tolerance" "1%" (at 349.25 149.86 0)
      (effects (font (size 1.27 1.27)) (justify left bottom) hide)
    )
    (pin "1")
    (pin "2")
    (instances
      (project "thunderbolt-pcie-adapter"
        (path ""
          (reference "R94") (unit 1)
        )
      )
    )
  )

  (symbol (lib_id "antmicropower:GND") (at 64.77 134.62 270) (unit 1)
    (in_bom yes) (on_board yes) (dnp no)
    (property "Reference" "#PWR024" (at 58.42 134.62 0)
      (effects (font (size 1.27 1.27)) hide)
    )
    (property "Value" "GND" (at 60.325 132.715 0)
      (effects (font (size 1.27 1.27) (thickness 0.15)) (justify left bottom))
    )
    (property "Footprint" "" (at 64.77 134.62 0)
      (effects (font (size 1.27 1.27) (thickness 0.15)) (justify left bottom) hide)
    )
    (property "Datasheet" "" (at 64.77 134.62 0)
      (effects (font (size 1.27 1.27) (thickness 0.15)) (justify left bottom) hide)
    )
    (property "Author" "Antmicro" (at 57.15 143.51 0)
      (effects (font (size 1.27 1.27) (thickness 0.15)) (justify left bottom) hide)
    )
    (property "License" "Apache-2.0" (at 54.61 143.51 0)
      (effects (font (size 1.27 1.27) (thickness 0.15)) (justify left bottom) hide)
    )
    (pin "1")
    (instances
      (project "thunderbolt-pcie-adapter"
        (path ""
          (reference "#PWR024") (unit 1)
        )
      )
    )
  )

  (symbol (lib_id "antmicroResistors0402:R_8k87_0402") (at 339.09 74.93 90) (unit 1)
    (in_bom yes) (on_board yes) (dnp no)
    (property "Reference" "R37" (at 340.36 71.12 90)
      (effects (font (size 1.27 1.27) (thickness 0.15)) (justify right))
    )
    (property "Value" "R_8k87_0402" (at 351.79 54.61 0)
      (effects (font (size 1.27 1.27) (thickness 0.15)) (justify left bottom) hide)
    )
    (property "Footprint" "antmicro-footprints:R_0402_1005Metric" (at 354.33 54.61 0)
      (effects (font (size 1.27 1.27) (thickness 0.15)) (justify left bottom) hide)
    )
    (property "Datasheet" "https://www.bourns.com/docs/product-datasheets/cr.pdf" (at 356.87 54.61 0)
      (effects (font (size 1.27 1.27) (thickness 0.15)) (justify left bottom) hide)
    )
    (property "MPN" "CR0402-FX-8871GLF" (at 359.41 54.61 0)
      (effects (font (size 1.27 1.27) (thickness 0.15)) (justify left bottom) hide)
    )
    (property "Manufacturer" "Bourns" (at 361.95 54.61 0)
      (effects (font (size 1.27 1.27) (thickness 0.15)) (justify left bottom) hide)
    )
    (property "License" "Apache-2.0" (at 364.49 54.61 0)
      (effects (font (size 1.27 1.27) (thickness 0.15)) (justify left bottom) hide)
    )
    (property "Val" "8k87" (at 345.44 72.39 90)
      (effects (font (size 1.27 1.27) (thickness 0.15)) (justify left bottom))
    )
    (property "Tolerance" "1%" (at 349.25 54.61 0)
      (effects (font (size 1.27 1.27)) (justify left bottom) hide)
    )
    (property "Author" "Antmicro" (at 367.03 54.61 0)
      (effects (font (size 1.27 1.27) (thickness 0.15)) (justify left bottom) hide)
    )
    (pin "1")
    (pin "2")
    (instances
      (project "thunderbolt-pcie-adapter"
        (path ""
          (reference "R37") (unit 1)
        )
      )
    )
  )

  (symbol (lib_id "antmicropower:GND") (at 180.34 222.25 0) (unit 1)
    (in_bom yes) (on_board yes) (dnp no)
    (property "Reference" "#PWR0177" (at 180.34 228.6 0)
      (effects (font (size 1.27 1.27)) hide)
    )
    (property "Value" "GND" (at 173.99 224.79 0)
      (effects (font (size 1.27 1.27) (thickness 0.15)) (justify left bottom))
    )
    (property "Footprint" "" (at 180.34 222.25 0)
      (effects (font (size 1.27 1.27) (thickness 0.15)) (justify left bottom) hide)
    )
    (property "Datasheet" "" (at 180.34 222.25 0)
      (effects (font (size 1.27 1.27) (thickness 0.15)) (justify left bottom) hide)
    )
    (property "Author" "Antmicro" (at 189.23 229.87 0)
      (effects (font (size 1.27 1.27) (thickness 0.15)) (justify left bottom) hide)
    )
    (property "License" "Apache-2.0" (at 189.23 232.41 0)
      (effects (font (size 1.27 1.27) (thickness 0.15)) (justify left bottom) hide)
    )
    (pin "1")
    (instances
      (project "thunderbolt-pcie-adapter"
        (path ""
          (reference "#PWR0177") (unit 1)
        )
      )
    )
  )

  (symbol (lib_id "antmicropower:GND") (at 142.24 60.96 90) (unit 1)
    (in_bom yes) (on_board yes) (dnp no)
    (property "Reference" "#PWR044" (at 148.59 60.96 0)
      (effects (font (size 1.27 1.27)) hide)
    )
    (property "Value" "GND" (at 146.685 62.865 0)
      (effects (font (size 1.27 1.27) (thickness 0.15)) (justify left bottom))
    )
    (property "Footprint" "" (at 142.24 60.96 0)
      (effects (font (size 1.27 1.27) (thickness 0.15)) (justify left bottom) hide)
    )
    (property "Datasheet" "" (at 142.24 60.96 0)
      (effects (font (size 1.27 1.27) (thickness 0.15)) (justify left bottom) hide)
    )
    (property "Author" "Antmicro" (at 149.86 52.07 0)
      (effects (font (size 1.27 1.27) (thickness 0.15)) (justify left bottom) hide)
    )
    (property "License" "Apache-2.0" (at 152.4 52.07 0)
      (effects (font (size 1.27 1.27) (thickness 0.15)) (justify left bottom) hide)
    )
    (pin "1")
    (instances
      (project "thunderbolt-pcie-adapter"
        (path ""
          (reference "#PWR044") (unit 1)
        )
      )
    )
  )

  (symbol (lib_id "antmicroPMICORControllersIdealDiodes:DZDH0401DW") (at 340.36 158.75 0) (unit 1)
    (in_bom yes) (on_board yes) (dnp no)
    (property "Reference" "Q4" (at 348.615 153.035 0)
      (effects (font (size 1.524 1.524)))
    )
    (property "Value" "DZDH0401DW" (at 370.84 166.37 0)
      (effects (font (size 1.27 1.27) (thickness 0.15)) (justify left bottom) hide)
    )
    (property "Footprint" "antmicro-footprints:SOT-363" (at 370.84 168.91 0)
      (effects (font (size 1.27 1.27) (thickness 0.15)) (justify left bottom) hide)
    )
    (property "Datasheet" "https://www.mouser.com/datasheet/2/115/DIOD_S_A0011803041_1-2543705.pdf" (at 370.84 171.45 0)
      (effects (font (size 1.27 1.27) (thickness 0.15)) (justify left bottom) hide)
    )
    (property "MPN" "DZDH0401DW" (at 342.265 156.21 0)
      (effects (font (size 1.27 1.27) (thickness 0.15)) (justify left bottom))
    )
    (property "Manufacturer" "Diodes Incorporated" (at 370.84 176.53 0)
      (effects (font (size 1.27 1.27) (thickness 0.15)) (justify left bottom) hide)
    )
    (property "Author" "Antmicro" (at 370.84 179.07 0)
      (effects (font (size 1.27 1.27) (thickness 0.15)) (justify left bottom) hide)
    )
    (property "License" "Apache-2.0" (at 370.84 181.61 0)
      (effects (font (size 1.27 1.27) (thickness 0.15)) (justify left bottom) hide)
    )
    (pin "2")
    (pin "3")
    (pin "4")
    (pin "6")
    (instances
      (project "thunderbolt-pcie-adapter"
        (path ""
          (reference "Q4") (unit 1)
        )
      )
    )
  )

  (symbol (lib_id "antmicroResistors0402:R_100k_0402") (at 137.16 121.92 0) (unit 1)
    (in_bom yes) (on_board yes) (dnp no)
    (property "Reference" "R29" (at 139.7 120.015 0)
      (effects (font (size 1.27 1.27) (thickness 0.15)))
    )
    (property "Value" "R_100k_0402" (at 157.48 134.62 0)
      (effects (font (size 1.27 1.27) (thickness 0.15)) (justify left bottom) hide)
    )
    (property "Footprint" "antmicro-footprints:R_0402_1005Metric" (at 157.48 137.16 0)
      (effects (font (size 1.27 1.27) (thickness 0.15)) (justify left bottom) hide)
    )
    (property "Datasheet" "https://www.bourns.com/docs/product-datasheets/cr.pdf" (at 157.48 139.7 0)
      (effects (font (size 1.27 1.27) (thickness 0.15)) (justify left bottom) hide)
    )
    (property "MPN" "CR0402-FX-1003GLF" (at 157.48 142.24 0)
      (effects (font (size 1.27 1.27) (thickness 0.15)) (justify left bottom) hide)
    )
    (property "Manufacturer" "Bourns" (at 157.48 144.78 0)
      (effects (font (size 1.27 1.27) (thickness 0.15)) (justify left bottom) hide)
    )
    (property "License" "Apache-2.0" (at 157.48 147.32 0)
      (effects (font (size 1.27 1.27) (thickness 0.15)) (justify left bottom) hide)
    )
    (property "Val" "100k" (at 141.605 121.285 0)
      (effects (font (size 1.27 1.27) (thickness 0.15)) (justify left bottom))
    )
    (property "Tolerance" "1%" (at 157.48 132.08 0)
      (effects (font (size 1.27 1.27)) (justify left bottom) hide)
    )
    (property "Author" "Antmicro" (at 157.48 149.86 0)
      (effects (font (size 1.27 1.27) (thickness 0.15)) (justify left bottom) hide)
    )
    (pin "1")
    (pin "2")
    (instances
      (project "thunderbolt-pcie-adapter"
        (path ""
          (reference "R29") (unit 1)
        )
      )
    )
  )

  (symbol (lib_id "antmicroCapacitorsmisc:C_22u_1206_35V") (at 271.78 50.8 90) (unit 1)
    (in_bom yes) (on_board yes) (dnp no)
    (property "Reference" "C17" (at 272.415 46.355 90)
      (effects (font (size 1.27 1.27) (thickness 0.15)) (justify right))
    )
    (property "Value" "C_22u_1206_35V" (at 281.94 30.48 0)
      (effects (font (size 1.27 1.27) (thickness 0.15)) (justify left bottom) hide)
    )
    (property "Footprint" "antmicro-footprints:C_1206_3216Metric" (at 284.48 30.48 0)
      (effects (font (size 1.27 1.27) (thickness 0.15)) (justify left bottom) hide)
    )
    (property "Datasheet" "https://product.tdk.com/en/search/capacitor/ceramic/mlcc/info?part_no=3216X5R1V226M160AC" (at 287.02 30.48 0)
      (effects (font (size 1.27 1.27) (thickness 0.15)) (justify left bottom) hide)
    )
    (property "MPN" "3216X5R1V226M160AC" (at 289.56 30.48 0)
      (effects (font (size 1.27 1.27) (thickness 0.15)) (justify left bottom) hide)
    )
    (property "Manufacturer" "TDK" (at 292.1 30.48 0)
      (effects (font (size 1.27 1.27) (thickness 0.15)) (justify left bottom) hide)
    )
    (property "License" "Apache-2.0" (at 294.64 30.48 0)
      (effects (font (size 1.27 1.27) (thickness 0.15)) (justify left bottom) hide)
    )
    (property "Val" "22u" (at 276.225 50.165 90)
      (effects (font (size 1.27 1.27) (thickness 0.15)) (justify left bottom))
    )
    (property "Voltage" "35V" (at 299.72 30.48 0)
      (effects (font (size 1.27 1.27)) (justify left bottom) hide)
    )
    (property "Dielectric" "" (at 302.26 30.48 0)
      (effects (font (size 1.27 1.27)) (justify left bottom) hide)
    )
    (property "Author" "Antmicro" (at 297.18 30.48 0)
      (effects (font (size 1.27 1.27) (thickness 0.15)) (justify left bottom) hide)
    )
    (pin "1")
    (pin "2")
    (instances
      (project "thunderbolt-pcie-adapter"
        (path ""
          (reference "C17") (unit 1)
        )
      )
    )
  )

  (symbol (lib_id "antmicropower:GND") (at 219.71 220.98 0) (unit 1)
    (in_bom yes) (on_board yes) (dnp no)
    (property "Reference" "#PWR0182" (at 219.71 227.33 0)
      (effects (font (size 1.27 1.27)) hide)
    )
    (property "Value" "GND" (at 217.805 225.425 0)
      (effects (font (size 1.27 1.27) (thickness 0.15)) (justify left bottom))
    )
    (property "Footprint" "" (at 219.71 220.98 0)
      (effects (font (size 1.27 1.27) (thickness 0.15)) (justify left bottom) hide)
    )
    (property "Datasheet" "" (at 219.71 220.98 0)
      (effects (font (size 1.27 1.27) (thickness 0.15)) (justify left bottom) hide)
    )
    (property "Author" "Antmicro" (at 228.6 228.6 0)
      (effects (font (size 1.27 1.27) (thickness 0.15)) (justify left bottom) hide)
    )
    (property "License" "Apache-2.0" (at 228.6 231.14 0)
      (effects (font (size 1.27 1.27) (thickness 0.15)) (justify left bottom) hide)
    )
    (pin "1")
    (instances
      (project "thunderbolt-pcie-adapter"
        (path ""
          (reference "#PWR0182") (unit 1)
        )
      )
    )
  )

  (symbol (lib_id "antmicroShuntsJumpers:Net-Tie_P0.127mm") (at 257.81 214.63 270) (unit 1)
    (in_bom no) (on_board yes) (dnp no)
    (property "Reference" "TP11" (at 258.445 217.805 90)
      (effects (font (size 1.27 1.27) (thickness 0.15)) (justify left))
    )
    (property "Value" "Net-Tie_P0.127mm" (at 259.715 219.075 90)
      (effects (font (size 1.27 1.27) (thickness 0.15)) (justify left) hide)
    )
    (property "Footprint" "antmicro-footprints:NetTie-2_SMD_Pad0.127mm" (at 245.11 236.22 0)
      (effects (font (size 1.27 1.27) (thickness 0.15)) (justify left bottom) hide)
    )
    (property "Datasheet" "" (at 242.57 236.22 0)
      (effects (font (size 1.27 1.27) (thickness 0.15)) (justify left bottom) hide)
    )
    (property "MPN" "" (at 247.65 236.22 0)
      (effects (font (size 1.27 1.27) (thickness 0.15)) (justify left bottom))
    )
    (property "Manufacturer" "" (at 240.03 236.22 0)
      (effects (font (size 1.27 1.27) (thickness 0.15)) (justify left bottom) hide)
    )
    (property "Author" "Antmicro" (at 237.49 236.22 0)
      (effects (font (size 1.27 1.27) (thickness 0.15)) (justify left bottom) hide)
    )
    (property "License" "Apache-2.0" (at 234.95 236.22 0)
      (effects (font (size 1.27 1.27) (thickness 0.15)) (justify left bottom) hide)
    )
    (pin "1")
    (pin "2")
    (instances
      (project "thunderbolt-pcie-adapter"
        (path ""
          (reference "TP11") (unit 1)
        )
      )
    )
  )

  (symbol (lib_id "antmicroResistors0402:R_100k_0402") (at 308.61 72.39 0) (unit 1)
    (in_bom yes) (on_board yes) (dnp no)
    (property "Reference" "R23" (at 313.055 70.485 0)
      (effects (font (size 1.27 1.27) (thickness 0.15)) (justify right))
    )
    (property "Value" "R_100k_0402" (at 328.93 85.09 0)
      (effects (font (size 1.27 1.27) (thickness 0.15)) (justify left bottom) hide)
    )
    (property "Footprint" "antmicro-footprints:R_0402_1005Metric" (at 328.93 87.63 0)
      (effects (font (size 1.27 1.27) (thickness 0.15)) (justify left bottom) hide)
    )
    (property "Datasheet" "https://www.bourns.com/docs/product-datasheets/cr.pdf" (at 328.93 90.17 0)
      (effects (font (size 1.27 1.27) (thickness 0.15)) (justify left bottom) hide)
    )
    (property "MPN" "CR0402-FX-1003GLF" (at 328.93 92.71 0)
      (effects (font (size 1.27 1.27) (thickness 0.15)) (justify left bottom) hide)
    )
    (property "Manufacturer" "Bourns" (at 328.93 95.25 0)
      (effects (font (size 1.27 1.27) (thickness 0.15)) (justify left bottom) hide)
    )
    (property "License" "Apache-2.0" (at 328.93 97.79 0)
      (effects (font (size 1.27 1.27) (thickness 0.15)) (justify left bottom) hide)
    )
    (property "Val" "100k" (at 308.61 75.565 0)
      (effects (font (size 1.27 1.27) (thickness 0.15)) (justify left bottom))
    )
    (property "Tolerance" "1%" (at 328.93 82.55 0)
      (effects (font (size 1.27 1.27)) (justify left bottom) hide)
    )
    (property "Author" "Antmicro" (at 328.93 100.33 0)
      (effects (font (size 1.27 1.27) (thickness 0.15)) (justify left bottom) hide)
    )
    (pin "1")
    (pin "2")
    (instances
      (project "thunderbolt-pcie-adapter"
        (path ""
          (reference "R23") (unit 1)
        )
      )
    )
  )

  (symbol (lib_id "antmicroCapacitors0402:C_220n_0402") (at 308.61 57.15 0) (unit 1)
    (in_bom yes) (on_board yes) (dnp no)
    (property "Reference" "C27" (at 308.61 55.88 0)
      (effects (font (size 1.27 1.27) (thickness 0.15)))
    )
    (property "Value" "C_220n_0402" (at 328.93 67.31 0)
      (effects (font (size 1.27 1.27) (thickness 0.15)) (justify left bottom) hide)
    )
    (property "Footprint" "antmicro-footprints:C_0402_1005Metric" (at 328.93 69.85 0)
      (effects (font (size 1.27 1.27) (thickness 0.15)) (justify left bottom) hide)
    )
    (property "Datasheet" "https://www.yageo.com/en/Chart/Download/pdf/CC0402KRX5R6BB224" (at 328.93 72.39 0)
      (effects (font (size 1.27 1.27) (thickness 0.15)) (justify left bottom) hide)
    )
    (property "MPN" "CC0402KRX5R6BB224" (at 328.93 74.93 0)
      (effects (font (size 1.27 1.27) (thickness 0.15)) (justify left bottom) hide)
    )
    (property "Manufacturer" "YAGEO" (at 328.93 77.47 0)
      (effects (font (size 1.27 1.27) (thickness 0.15)) (justify left bottom) hide)
    )
    (property "License" "Apache-2.0" (at 328.93 80.01 0)
      (effects (font (size 1.27 1.27) (thickness 0.15)) (justify left bottom) hide)
    )
    (property "Val" "220n" (at 312.42 56.515 0)
      (effects (font (size 1.27 1.27) (thickness 0.15)) (justify left bottom))
    )
    (property "Voltage" "" (at 328.93 85.09 0)
      (effects (font (size 1.27 1.27)) (justify left bottom) hide)
    )
    (property "Dielectric" "" (at 328.93 87.63 0)
      (effects (font (size 1.27 1.27)) (justify left bottom) hide)
    )
    (property "Author" "Antmicro" (at 328.93 82.55 0)
      (effects (font (size 1.27 1.27) (thickness 0.15)) (justify left bottom) hide)
    )
    (pin "1")
    (pin "2")
    (instances
      (project "thunderbolt-pcie-adapter"
        (path ""
          (reference "C27") (unit 1)
        )
      )
    )
  )

  (symbol (lib_id "antmicropower:GND") (at 142.24 66.04 90) (unit 1)
    (in_bom yes) (on_board yes) (dnp no)
    (property "Reference" "#PWR047" (at 148.59 66.04 0)
      (effects (font (size 1.27 1.27)) hide)
    )
    (property "Value" "GND" (at 146.685 67.945 0)
      (effects (font (size 1.27 1.27) (thickness 0.15)) (justify left bottom))
    )
    (property "Footprint" "" (at 142.24 66.04 0)
      (effects (font (size 1.27 1.27) (thickness 0.15)) (justify left bottom) hide)
    )
    (property "Datasheet" "" (at 142.24 66.04 0)
      (effects (font (size 1.27 1.27) (thickness 0.15)) (justify left bottom) hide)
    )
    (property "Author" "Antmicro" (at 149.86 57.15 0)
      (effects (font (size 1.27 1.27) (thickness 0.15)) (justify left bottom) hide)
    )
    (property "License" "Apache-2.0" (at 152.4 57.15 0)
      (effects (font (size 1.27 1.27) (thickness 0.15)) (justify left bottom) hide)
    )
    (pin "1")
    (instances
      (project "thunderbolt-pcie-adapter"
        (path ""
          (reference "#PWR047") (unit 1)
        )
      )
    )
  )

  (symbol (lib_id "antmicroResistors0402:R_0R_0402") (at 137.16 129.54 0) (unit 1)
    (in_bom yes) (on_board yes) (dnp no)
    (property "Reference" "R31" (at 139.7 132.08 0)
      (effects (font (size 1.27 1.27) (thickness 0.15)))
    )
    (property "Value" "R_0R_0402" (at 157.48 142.24 0)
      (effects (font (size 1.27 1.27) (thickness 0.15)) (justify left bottom) hide)
    )
    (property "Footprint" "antmicro-footprints:R_0402_1005Metric" (at 157.48 144.78 0)
      (effects (font (size 1.27 1.27) (thickness 0.15)) (justify left bottom) hide)
    )
    (property "Datasheet" "https://industrial.panasonic.com/cdbs/www-data/pdf/RDA0000/AOA0000C301.pdf" (at 157.48 147.32 0)
      (effects (font (size 1.27 1.27) (thickness 0.15)) (justify left bottom) hide)
    )
    (property "MPN" "ERJ2GE0R00X" (at 157.48 149.86 0)
      (effects (font (size 1.27 1.27) (thickness 0.15)) (justify left bottom) hide)
    )
    (property "Manufacturer" "Panasonic" (at 157.48 152.4 0)
      (effects (font (size 1.27 1.27) (thickness 0.15)) (justify left bottom) hide)
    )
    (property "License" "Apache-2.0" (at 157.48 154.94 0)
      (effects (font (size 1.27 1.27) (thickness 0.15)) (justify left bottom) hide)
    )
    (property "Val" "0R" (at 142.24 131.445 0)
      (effects (font (size 1.27 1.27) (thickness 0.15)) (justify left bottom))
    )
    (property "Tolerance" "~" (at 157.48 139.7 0)
      (effects (font (size 1.27 1.27)) (justify left bottom) hide)
    )
    (property "Current" "1A" (at 157.48 160.02 0)
      (effects (font (size 1.27 1.27) (thickness 0.15)) (justify left bottom) hide)
    )
    (property "Author" "Antmicro" (at 157.48 157.48 0)
      (effects (font (size 1.27 1.27) (thickness 0.15)) (justify left bottom) hide)
    )
    (pin "1")
    (pin "2")
    (instances
      (project "thunderbolt-pcie-adapter"
        (path ""
          (reference "R31") (unit 1)
        )
      )
    )
  )

  (symbol (lib_id "antmicropower:PWR_FLAG") (at 274.32 210.82 0) (unit 1)
    (in_bom yes) (on_board yes) (dnp no)
    (property "Reference" "#FLG04" (at 274.32 208.915 0)
      (effects (font (size 1.27 1.27)) hide)
    )
    (property "Value" "PWR_FLAG" (at 274.32 207.01 0)
      (effects (font (size 1.27 1.27)))
    )
    (property "Footprint" "" (at 274.32 210.82 0)
      (effects (font (size 1.27 1.27)) hide)
    )
    (property "Datasheet" "" (at 274.32 210.82 0)
      (effects (font (size 1.27 1.27)) hide)
    )
    (pin "1")
    (instances
      (project "thunderbolt-pcie-adapter"
        (path ""
          (reference "#FLG04") (unit 1)
        )
      )
    )
  )

  (symbol (lib_id "antmicropower:GND") (at 45.72 109.22 0) (unit 1)
    (in_bom yes) (on_board yes) (dnp no)
    (property "Reference" "#PWR013" (at 45.72 115.57 0)
      (effects (font (size 1.27 1.27)) hide)
    )
    (property "Value" "GND" (at 43.815 113.665 0)
      (effects (font (size 1.27 1.27) (thickness 0.15)) (justify left bottom))
    )
    (property "Footprint" "" (at 45.72 109.22 0)
      (effects (font (size 1.27 1.27) (thickness 0.15)) (justify left bottom) hide)
    )
    (property "Datasheet" "" (at 45.72 109.22 0)
      (effects (font (size 1.27 1.27) (thickness 0.15)) (justify left bottom) hide)
    )
    (property "Author" "Antmicro" (at 54.61 116.84 0)
      (effects (font (size 1.27 1.27) (thickness 0.15)) (justify left bottom) hide)
    )
    (property "License" "Apache-2.0" (at 54.61 119.38 0)
      (effects (font (size 1.27 1.27) (thickness 0.15)) (justify left bottom) hide)
    )
    (pin "1")
    (instances
      (project "thunderbolt-pcie-adapter"
        (path ""
          (reference "#PWR013") (unit 1)
        )
      )
    )
  )

  (symbol (lib_id "antmicroResistors0603:R_0R_22.4A_0603") (at 381 146.05 0) (unit 1)
    (in_bom yes) (on_board yes) (dnp no)
    (property "Reference" "R99" (at 383.54 144.145 0)
      (effects (font (size 1.27 1.27) (thickness 0.15)))
    )
    (property "Value" "R_0R_22.4A_0603" (at 382.27 151.13 0)
      (effects (font (size 1.27 1.27) (thickness 0.15)) hide)
    )
    (property "Footprint" "antmicro-footprints:R_0603_1608Metric" (at 396.24 156.21 0)
      (effects (font (size 1.27 1.27) (thickness 0.15)) (justify left bottom) hide)
    )
    (property "Datasheet" "https://fscdn.rohm.com/en/products/databook/datasheet/passive/resistor/chip_resistor/pmr-jpw-e.pdf" (at 396.24 158.75 0)
      (effects (font (size 1.27 1.27) (thickness 0.15)) (justify left bottom) hide)
    )
    (property "MPN" "PMR03EZPJ000" (at 396.24 161.29 0)
      (effects (font (size 1.27 1.27) (thickness 0.15)) (justify left bottom) hide)
    )
    (property "Manufacturer" "ROHM Semiconductor" (at 396.24 163.83 0)
      (effects (font (size 1.27 1.27) (thickness 0.15)) (justify left bottom) hide)
    )
    (property "Val" "0R" (at 381 148.59 0)
      (effects (font (size 1.27 1.27) (thickness 0.15)))
    )
    (property "Max. Curr." "22.4A" (at 386.715 148.59 0)
      (effects (font (size 1.27 1.27) (thickness 0.15)))
    )
    (property "Author" "Antmicro" (at 396.24 168.91 0)
      (effects (font (size 1.27 1.27) (thickness 0.15)) (justify left bottom) hide)
    )
    (property "License" "Apache-2.0" (at 396.24 171.45 0)
      (effects (font (size 1.27 1.27) (thickness 0.15)) (justify left bottom) hide)
    )
    (property "Tolerance" "template_tolerance" (at 401.32 156.21 0)
      (effects (font (size 1.27 1.27)) (justify left bottom) hide)
    )
    (pin "2")
    (pin "1")
    (instances
      (project "thunderbolt-pcie-adapter"
        (path ""
          (reference "R99") (unit 1)
        )
      )
    )
  )

  (symbol (lib_id "antmicroTestPoints:TP_1mm_SMD") (at 123.19 224.79 90) (unit 1)
    (in_bom no) (on_board yes) (dnp no)
    (property "Reference" "TP3" (at 124.46 222.25 90)
      (effects (font (size 1.27 1.27) (thickness 0.15)) (justify right))
    )
    (property "Value" "TP_1mm_SMD" (at 130.81 209.55 0)
      (effects (font (size 1.27 1.27) (thickness 0.15)) (justify left bottom) hide)
    )
    (property "Footprint" "antmicro-footprints:TP_SMD_1mm" (at 133.35 209.55 0)
      (effects (font (size 1.27 1.27) (thickness 0.15)) (justify left bottom) hide)
    )
    (property "Datasheet" "" (at 135.89 207.01 0)
      (effects (font (size 1.27 1.27) (thickness 0.15)) (justify left bottom) hide)
    )
    (property "License" "Apache-2.0" (at 140.97 209.55 0)
      (effects (font (size 1.27 1.27) (thickness 0.15)) (justify left bottom) hide)
    )
    (property "Manufacturer" "" (at 123.19 224.79 0)
      (effects (font (size 1.27 1.27)) hide)
    )
    (property "MPN" "" (at 123.19 224.79 0)
      (effects (font (size 1.27 1.27)) hide)
    )
    (property "Author" "Antmicro" (at 138.43 209.55 0)
      (effects (font (size 1.27 1.27) (thickness 0.15)) (justify left bottom) hide)
    )
    (pin "1")
    (instances
      (project "thunderbolt-pcie-adapter"
        (path ""
          (reference "TP3") (unit 1)
        )
      )
    )
  )

  (symbol (lib_id "antmicroTestPoints:TP_1mm_SMD") (at 264.16 212.09 90) (unit 1)
    (in_bom no) (on_board yes) (dnp no)
    (property "Reference" "TP8" (at 262.89 207.01 90)
      (effects (font (size 1.27 1.27) (thickness 0.15)) (justify right))
    )
    (property "Value" "TP_1mm_SMD" (at 271.78 196.85 0)
      (effects (font (size 1.27 1.27) (thickness 0.15)) (justify left bottom) hide)
    )
    (property "Footprint" "antmicro-footprints:TP_SMD_1mm" (at 274.32 196.85 0)
      (effects (font (size 1.27 1.27) (thickness 0.15)) (justify left bottom) hide)
    )
    (property "Datasheet" "" (at 276.86 194.31 0)
      (effects (font (size 1.27 1.27) (thickness 0.15)) (justify left bottom) hide)
    )
    (property "License" "Apache-2.0" (at 281.94 196.85 0)
      (effects (font (size 1.27 1.27) (thickness 0.15)) (justify left bottom) hide)
    )
    (property "Manufacturer" "" (at 264.16 212.09 0)
      (effects (font (size 1.27 1.27)) hide)
    )
    (property "MPN" "" (at 264.16 212.09 0)
      (effects (font (size 1.27 1.27)) hide)
    )
    (property "Author" "Antmicro" (at 279.4 196.85 0)
      (effects (font (size 1.27 1.27) (thickness 0.15)) (justify left bottom) hide)
    )
    (pin "1")
    (instances
      (project "thunderbolt-pcie-adapter"
        (path ""
          (reference "TP8") (unit 1)
        )
      )
    )
  )

  (symbol (lib_id "antmicroResistors0402:R_1M_0402") (at 66.04 134.62 0) (unit 1)
    (in_bom yes) (on_board yes) (dnp no)
    (property "Reference" "R21" (at 68.58 132.715 0)
      (effects (font (size 1.27 1.27) (thickness 0.15)))
    )
    (property "Value" "R_1M_0402" (at 86.36 147.32 0)
      (effects (font (size 1.27 1.27) (thickness 0.15)) (justify left bottom) hide)
    )
    (property "Footprint" "antmicro-footprints:R_0402_1005Metric" (at 86.36 149.86 0)
      (effects (font (size 1.27 1.27) (thickness 0.15)) (justify left bottom) hide)
    )
    (property "Datasheet" "https://www.bourns.com/docs/product-datasheets/cr.pdf" (at 86.36 152.4 0)
      (effects (font (size 1.27 1.27) (thickness 0.15)) (justify left bottom) hide)
    )
    (property "MPN" "CR0402-FX-1004GLF" (at 86.36 154.94 0)
      (effects (font (size 1.27 1.27) (thickness 0.15)) (justify left bottom) hide)
    )
    (property "Manufacturer" "Bourns" (at 86.36 157.48 0)
      (effects (font (size 1.27 1.27) (thickness 0.15)) (justify left bottom) hide)
    )
    (property "License" "Apache-2.0" (at 86.36 160.02 0)
      (effects (font (size 1.27 1.27) (thickness 0.15)) (justify left bottom) hide)
    )
    (property "Val" "1M" (at 67.31 137.795 0)
      (effects (font (size 1.27 1.27) (thickness 0.15)) (justify left bottom))
    )
    (property "Tolerance" "1%" (at 86.36 144.78 0)
      (effects (font (size 1.27 1.27)) (justify left bottom) hide)
    )
    (property "Author" "Antmicro" (at 86.36 162.56 0)
      (effects (font (size 1.27 1.27) (thickness 0.15)) (justify left bottom) hide)
    )
    (pin "1")
    (pin "2")
    (instances
      (project "thunderbolt-pcie-adapter"
        (path ""
          (reference "R21") (unit 1)
        )
      )
    )
  )

  (symbol (lib_id "antmicroCapacitors0402:C_33p_0402") (at 330.2 66.04 90) (unit 1)
    (in_bom yes) (on_board yes) (dnp no)
    (property "Reference" "C33" (at 332.105 62.23 90)
      (effects (font (size 1.27 1.27) (thickness 0.15)) (justify right))
    )
    (property "Value" "C_33p_0402" (at 340.36 45.72 0)
      (effects (font (size 1.27 1.27) (thickness 0.15)) (justify left bottom) hide)
    )
    (property "Footprint" "antmicro-footprints:C_0402_1005Metric" (at 342.9 45.72 0)
      (effects (font (size 1.27 1.27) (thickness 0.15)) (justify left bottom) hide)
    )
    (property "Datasheet" "https://spicat.kyocera-avx.com/product/mlcc/chartview/04025A330FAT2A/" (at 345.44 45.72 0)
      (effects (font (size 1.27 1.27) (thickness 0.15)) (justify left bottom) hide)
    )
    (property "MPN" "04025A330FAT2A" (at 347.98 45.72 0)
      (effects (font (size 1.27 1.27) (thickness 0.15)) (justify left bottom) hide)
    )
    (property "Manufacturer" "KYOCERA AVX" (at 350.52 45.72 0)
      (effects (font (size 1.27 1.27) (thickness 0.15)) (justify left bottom) hide)
    )
    (property "License" "Apache-2.0" (at 353.06 45.72 0)
      (effects (font (size 1.27 1.27) (thickness 0.15)) (justify left bottom) hide)
    )
    (property "Val" "33p" (at 335.915 63.5 90)
      (effects (font (size 1.27 1.27) (thickness 0.15)) (justify left bottom))
    )
    (property "Voltage" "" (at 358.14 45.72 0)
      (effects (font (size 1.27 1.27)) (justify left bottom) hide)
    )
    (property "Dielectric" "" (at 360.68 45.72 0)
      (effects (font (size 1.27 1.27)) (justify left bottom) hide)
    )
    (property "Author" "Antmicro" (at 355.6 45.72 0)
      (effects (font (size 1.27 1.27) (thickness 0.15)) (justify left bottom) hide)
    )
    (pin "1")
    (pin "2")
    (instances
      (project "thunderbolt-pcie-adapter"
        (path ""
          (reference "C33") (unit 1)
        )
      )
    )
  )

  (symbol (lib_id "antmicroResistors0402:R_0R_0402") (at 127 247.65 0) (mirror x) (unit 1)
    (in_bom yes) (on_board yes) (dnp no)
    (property "Reference" "R13" (at 125.73 246.38 0)
      (effects (font (size 1.27 1.27) (thickness 0.15)))
    )
    (property "Value" "R_0R_0402" (at 147.32 234.95 0)
      (effects (font (size 1.27 1.27) (thickness 0.15)) (justify left bottom) hide)
    )
    (property "Footprint" "antmicro-footprints:R_0402_1005Metric" (at 147.32 232.41 0)
      (effects (font (size 1.27 1.27) (thickness 0.15)) (justify left bottom) hide)
    )
    (property "Datasheet" "https://industrial.panasonic.com/cdbs/www-data/pdf/RDA0000/AOA0000C301.pdf" (at 147.32 229.87 0)
      (effects (font (size 1.27 1.27) (thickness 0.15)) (justify left bottom) hide)
    )
    (property "MPN" "ERJ2GE0R00X" (at 147.32 227.33 0)
      (effects (font (size 1.27 1.27) (thickness 0.15)) (justify left bottom) hide)
    )
    (property "Manufacturer" "Panasonic" (at 147.32 224.79 0)
      (effects (font (size 1.27 1.27) (thickness 0.15)) (justify left bottom) hide)
    )
    (property "License" "Apache-2.0" (at 147.32 222.25 0)
      (effects (font (size 1.27 1.27) (thickness 0.15)) (justify left bottom) hide)
    )
    (property "Val" "0R" (at 132.08 245.745 0)
      (effects (font (size 1.27 1.27) (thickness 0.15)) (justify left bottom))
    )
    (property "Tolerance" "~" (at 147.32 237.49 0)
      (effects (font (size 1.27 1.27)) (justify left bottom) hide)
    )
    (property "Current" "1A" (at 147.32 217.17 0)
      (effects (font (size 1.27 1.27) (thickness 0.15)) (justify left bottom) hide)
    )
    (property "Author" "Antmicro" (at 147.32 219.71 0)
      (effects (font (size 1.27 1.27) (thickness 0.15)) (justify left bottom) hide)
    )
    (pin "1")
    (pin "2")
    (instances
      (project "thunderbolt-pcie-adapter"
        (path ""
          (reference "R13") (unit 1)
        )
      )
    )
  )

  (symbol (lib_id "antmicroResistors0402:R_0R_0402") (at 130.81 252.73 270) (unit 1)
    (in_bom yes) (on_board yes) (dnp no)
    (property "Reference" "R27" (at 128.27 254 90)
      (effects (font (size 1.27 1.27) (thickness 0.15)) (justify right))
    )
    (property "Value" "R_0R_0402" (at 118.11 273.05 0)
      (effects (font (size 1.27 1.27) (thickness 0.15)) (justify left bottom) hide)
    )
    (property "Footprint" "antmicro-footprints:R_0402_1005Metric" (at 115.57 273.05 0)
      (effects (font (size 1.27 1.27) (thickness 0.15)) (justify left bottom) hide)
    )
    (property "Datasheet" "https://industrial.panasonic.com/cdbs/www-data/pdf/RDA0000/AOA0000C301.pdf" (at 113.03 273.05 0)
      (effects (font (size 1.27 1.27) (thickness 0.15)) (justify left bottom) hide)
    )
    (property "MPN" "ERJ2GE0R00X" (at 110.49 273.05 0)
      (effects (font (size 1.27 1.27) (thickness 0.15)) (justify left bottom) hide)
    )
    (property "Manufacturer" "Panasonic" (at 107.95 273.05 0)
      (effects (font (size 1.27 1.27) (thickness 0.15)) (justify left bottom) hide)
    )
    (property "License" "Apache-2.0" (at 105.41 273.05 0)
      (effects (font (size 1.27 1.27) (thickness 0.15)) (justify left bottom) hide)
    )
    (property "Val" "0R" (at 128.27 256.54 90)
      (effects (font (size 1.27 1.27) (thickness 0.15)) (justify right))
    )
    (property "Tolerance" "~" (at 120.65 273.05 0)
      (effects (font (size 1.27 1.27)) (justify left bottom) hide)
    )
    (property "Current" "1A" (at 100.33 273.05 0)
      (effects (font (size 1.27 1.27) (thickness 0.15)) (justify left bottom) hide)
    )
    (property "Author" "Antmicro" (at 102.87 273.05 0)
      (effects (font (size 1.27 1.27) (thickness 0.15)) (justify left bottom) hide)
    )
    (pin "1")
    (pin "2")
    (instances
      (project "thunderbolt-pcie-adapter"
        (path ""
          (reference "R27") (unit 1)
        )
      )
    )
  )

  (symbol (lib_id "antmicroResistors0402:R_2k2_0402") (at 41.91 64.77 90) (unit 1)
    (in_bom yes) (on_board yes) (dnp no) (fields_autoplaced)
    (property "Reference" "R5" (at 43.18 60.96 90)
      (effects (font (size 1.27 1.27) (thickness 0.15)) (justify right))
    )
    (property "Value" "R_2k2_0402" (at 54.61 44.45 0)
      (effects (font (size 1.27 1.27) (thickness 0.15)) (justify left bottom) hide)
    )
    (property "Footprint" "antmicro-footprints:R_0402_1005Metric" (at 57.15 44.45 0)
      (effects (font (size 1.27 1.27) (thickness 0.15)) (justify left bottom) hide)
    )
    (property "Datasheet" "https://www.bourns.com/docs/product-datasheets/cr.pdf" (at 59.69 44.45 0)
      (effects (font (size 1.27 1.27) (thickness 0.15)) (justify left bottom) hide)
    )
    (property "MPN" "CR0402-FX-2201GLF" (at 62.23 44.45 0)
      (effects (font (size 1.27 1.27) (thickness 0.15)) (justify left bottom) hide)
    )
    (property "Manufacturer" "Bourns" (at 64.77 44.45 0)
      (effects (font (size 1.27 1.27) (thickness 0.15)) (justify left bottom) hide)
    )
    (property "License" "Apache-2.0" (at 67.31 44.45 0)
      (effects (font (size 1.27 1.27) (thickness 0.15)) (justify left bottom) hide)
    )
    (property "Val" "2k2" (at 46.355 62.23 90)
      (effects (font (size 1.27 1.27) (thickness 0.15)) (justify left bottom))
    )
    (property "Tolerance" "1%" (at 52.07 44.45 0)
      (effects (font (size 1.27 1.27)) (justify left bottom) hide)
    )
    (property "Author" "Antmicro" (at 69.85 44.45 0)
      (effects (font (size 1.27 1.27) (thickness 0.15)) (justify left bottom) hide)
    )
    (pin "1")
    (pin "2")
    (instances
      (project "thunderbolt-pcie-adapter"
        (path ""
          (reference "R5") (unit 1)
        )
      )
    )
  )

  (symbol (lib_id "antmicroResistors0402:R_5k1_0402") (at 176.53 83.82 90) (unit 1)
    (in_bom yes) (on_board yes) (dnp no)
    (property "Reference" "R40" (at 177.8 80.01 90)
      (effects (font (size 1.27 1.27) (thickness 0.15)) (justify right))
    )
    (property "Value" "R_5k1_0402" (at 189.23 63.5 0)
      (effects (font (size 1.27 1.27) (thickness 0.15)) (justify left bottom) hide)
    )
    (property "Footprint" "antmicro-footprints:R_0402_1005Metric" (at 191.77 63.5 0)
      (effects (font (size 1.27 1.27) (thickness 0.15)) (justify left bottom) hide)
    )
    (property "Datasheet" "https://www.bourns.com/docs/product-datasheets/cr.pdf" (at 194.31 63.5 0)
      (effects (font (size 1.27 1.27) (thickness 0.15)) (justify left bottom) hide)
    )
    (property "MPN" "CR0402-FX-5101GLF" (at 196.85 63.5 0)
      (effects (font (size 1.27 1.27) (thickness 0.15)) (justify left bottom) hide)
    )
    (property "Manufacturer" "Bourns" (at 199.39 63.5 0)
      (effects (font (size 1.27 1.27) (thickness 0.15)) (justify left bottom) hide)
    )
    (property "License" "Apache-2.0" (at 201.93 63.5 0)
      (effects (font (size 1.27 1.27) (thickness 0.15)) (justify left bottom) hide)
    )
    (property "Val" "5k1" (at 181.61 81.28 90)
      (effects (font (size 1.27 1.27) (thickness 0.15)) (justify left bottom))
    )
    (property "Tolerance" "1%" (at 186.69 63.5 0)
      (effects (font (size 1.27 1.27)) (justify left bottom) hide)
    )
    (property "Author" "Antmicro" (at 204.47 63.5 0)
      (effects (font (size 1.27 1.27) (thickness 0.15)) (justify left bottom) hide)
    )
    (pin "1")
    (pin "2")
    (instances
      (project "thunderbolt-pcie-adapter"
        (path ""
          (reference "R40") (unit 1)
        )
      )
    )
  )

  (symbol (lib_id "antmicroCapacitors0402:C_1u_0402") (at 135.89 45.72 0) (unit 1)
    (in_bom yes) (on_board yes) (dnp no)
    (property "Reference" "C34" (at 140.97 44.45 0)
      (effects (font (size 1.27 1.27) (thickness 0.15)))
    )
    (property "Value" "C_1u_0402" (at 156.21 55.88 0)
      (effects (font (size 1.27 1.27) (thickness 0.15)) (justify left bottom) hide)
    )
    (property "Footprint" "antmicro-footprints:C_0402_1005Metric" (at 156.21 58.42 0)
      (effects (font (size 1.27 1.27) (thickness 0.15)) (justify left bottom) hide)
    )
    (property "Datasheet" "https://product.tdk.com/en/search/capacitor/ceramic/mlcc/info?part_no=C1005X6S1A105K050BC" (at 156.21 60.96 0)
      (effects (font (size 1.27 1.27) (thickness 0.15)) (justify left bottom) hide)
    )
    (property "MPN" "C1005X6S1A105K050BC" (at 156.21 63.5 0)
      (effects (font (size 1.27 1.27) (thickness 0.15)) (justify left bottom) hide)
    )
    (property "Manufacturer" "TDK" (at 156.21 66.04 0)
      (effects (font (size 1.27 1.27) (thickness 0.15)) (justify left bottom) hide)
    )
    (property "License" "Apache-2.0" (at 156.21 68.58 0)
      (effects (font (size 1.27 1.27) (thickness 0.15)) (justify left bottom) hide)
    )
    (property "Val" "1u" (at 139.065 47.625 0)
      (effects (font (size 1.27 1.27) (thickness 0.15)) (justify left bottom))
    )
    (property "Voltage" "" (at 156.21 73.66 0)
      (effects (font (size 1.27 1.27)) (justify left bottom) hide)
    )
    (property "Dielectric" "" (at 156.21 76.2 0)
      (effects (font (size 1.27 1.27)) (justify left bottom) hide)
    )
    (property "Author" "Antmicro" (at 156.21 71.12 0)
      (effects (font (size 1.27 1.27) (thickness 0.15)) (justify left bottom) hide)
    )
    (pin "1")
    (pin "2")
    (instances
      (project "thunderbolt-pcie-adapter"
        (path ""
          (reference "C34") (unit 1)
        )
      )
    )
  )

  (symbol (lib_id "antmicropower:GND") (at 104.14 222.25 0) (unit 1)
    (in_bom yes) (on_board yes) (dnp no)
    (property "Reference" "#PWR0170" (at 104.14 228.6 0)
      (effects (font (size 1.27 1.27)) hide)
    )
    (property "Value" "GND" (at 102.235 226.695 0)
      (effects (font (size 1.27 1.27) (thickness 0.15)) (justify left bottom))
    )
    (property "Footprint" "" (at 104.14 222.25 0)
      (effects (font (size 1.27 1.27) (thickness 0.15)) (justify left bottom) hide)
    )
    (property "Datasheet" "" (at 104.14 222.25 0)
      (effects (font (size 1.27 1.27) (thickness 0.15)) (justify left bottom) hide)
    )
    (property "Author" "Antmicro" (at 113.03 229.87 0)
      (effects (font (size 1.27 1.27) (thickness 0.15)) (justify left bottom) hide)
    )
    (property "License" "Apache-2.0" (at 113.03 232.41 0)
      (effects (font (size 1.27 1.27) (thickness 0.15)) (justify left bottom) hide)
    )
    (pin "1")
    (instances
      (project "thunderbolt-pcie-adapter"
        (path ""
          (reference "#PWR0170") (unit 1)
        )
      )
    )
  )

  (symbol (lib_id "antmicroTestPoints:TP_1mm_SMD") (at 365.76 58.42 90) (unit 1)
    (in_bom no) (on_board yes) (dnp no)
    (property "Reference" "TP7" (at 363.855 53.34 90)
      (effects (font (size 1.27 1.27) (thickness 0.15)) (justify right))
    )
    (property "Value" "TP_1mm_SMD" (at 373.38 43.18 0)
      (effects (font (size 1.27 1.27) (thickness 0.15)) (justify left bottom) hide)
    )
    (property "Footprint" "antmicro-footprints:TP_SMD_1mm" (at 375.92 43.18 0)
      (effects (font (size 1.27 1.27) (thickness 0.15)) (justify left bottom) hide)
    )
    (property "Datasheet" "" (at 378.46 40.64 0)
      (effects (font (size 1.27 1.27) (thickness 0.15)) (justify left bottom) hide)
    )
    (property "License" "Apache-2.0" (at 383.54 43.18 0)
      (effects (font (size 1.27 1.27) (thickness 0.15)) (justify left bottom) hide)
    )
    (property "Manufacturer" "" (at 365.76 58.42 0)
      (effects (font (size 1.27 1.27)) hide)
    )
    (property "MPN" "" (at 365.76 58.42 0)
      (effects (font (size 1.27 1.27)) hide)
    )
    (property "Author" "Antmicro" (at 381 43.18 0)
      (effects (font (size 1.27 1.27) (thickness 0.15)) (justify left bottom) hide)
    )
    (pin "1")
    (instances
      (project "thunderbolt-pcie-adapter"
        (path ""
          (reference "TP7") (unit 1)
        )
      )
    )
  )

  (symbol (lib_id "antmicroCapacitors0603:C_22u_16V_0603") (at 49.53 266.7 90) (unit 1)
    (in_bom yes) (on_board yes) (dnp no)
    (property "Reference" "C119" (at 50.165 262.255 90)
      (effects (font (size 1.27 1.27) (thickness 0.15)) (justify right))
    )
    (property "Value" "C_22u_16V_0603" (at 59.69 246.38 0)
      (effects (font (size 1.27 1.27) (thickness 0.15)) (justify left bottom) hide)
    )
    (property "Footprint" "antmicro-footprints:C_0603_1608Metric" (at 62.23 246.38 0)
      (effects (font (size 1.27 1.27) (thickness 0.15)) (justify left bottom) hide)
    )
    (property "Datasheet" "https://product.samsungsem.com/mlcc/CL10A226MO7JZN.do" (at 64.77 246.38 0)
      (effects (font (size 1.27 1.27) (thickness 0.15)) (justify left bottom) hide)
    )
    (property "MPN" "CL10A226MO7JZNC" (at 67.31 246.38 0)
      (effects (font (size 1.27 1.27) (thickness 0.15)) (justify left bottom) hide)
    )
    (property "Manufacturer" "Samsung Electro-Mechanics" (at 69.85 246.38 0)
      (effects (font (size 1.27 1.27) (thickness 0.15)) (justify left bottom) hide)
    )
    (property "License" "Apache-2.0" (at 72.39 246.38 0)
      (effects (font (size 1.27 1.27) (thickness 0.15)) (justify left bottom) hide)
    )
    (property "Val" "22u" (at 55.245 263.525 90)
      (effects (font (size 1.27 1.27) (thickness 0.15)) (justify left bottom))
    )
    (property "Voltage" "16V" (at 77.47 246.38 0)
      (effects (font (size 1.27 1.27)) (justify left bottom) hide)
    )
    (property "Dielectric" "" (at 80.01 246.38 0)
      (effects (font (size 1.27 1.27)) (justify left bottom) hide)
    )
    (property "Author" "Antmicro" (at 74.93 246.38 0)
      (effects (font (size 1.27 1.27) (thickness 0.15)) (justify left bottom) hide)
    )
    (pin "1")
    (pin "2")
    (instances
      (project "thunderbolt-pcie-adapter"
        (path ""
          (reference "C119") (unit 1)
        )
      )
    )
  )

  (symbol (lib_id "antmicroResistors0402:R_10k_0402") (at 66.04 104.14 0) (unit 1)
    (in_bom yes) (on_board yes) (dnp no)
    (property "Reference" "R19" (at 68.58 102.235 0)
      (effects (font (size 1.27 1.27) (thickness 0.15)))
    )
    (property "Value" "R_10k_0402" (at 86.36 116.84 0)
      (effects (font (size 1.27 1.27) (thickness 0.15)) (justify left bottom) hide)
    )
    (property "Footprint" "antmicro-footprints:R_0402_1005Metric" (at 86.36 119.38 0)
      (effects (font (size 1.27 1.27) (thickness 0.15)) (justify left bottom) hide)
    )
    (property "Datasheet" "https://www.bourns.com/docs/product-datasheets/cr.pdf" (at 86.36 121.92 0)
      (effects (font (size 1.27 1.27) (thickness 0.15)) (justify left bottom) hide)
    )
    (property "MPN" "CR0402-FX-1002GLF" (at 86.36 124.46 0)
      (effects (font (size 1.27 1.27) (thickness 0.15)) (justify left bottom) hide)
    )
    (property "Manufacturer" "Bourns" (at 86.36 127 0)
      (effects (font (size 1.27 1.27) (thickness 0.15)) (justify left bottom) hide)
    )
    (property "License" "Apache-2.0" (at 86.36 129.54 0)
      (effects (font (size 1.27 1.27) (thickness 0.15)) (justify left bottom) hide)
    )
    (property "Val" "10k" (at 71.12 103.505 0)
      (effects (font (size 1.27 1.27) (thickness 0.15)) (justify left bottom))
    )
    (property "Tolerance" "1%" (at 86.36 114.3 0)
      (effects (font (size 1.27 1.27)) (justify left bottom) hide)
    )
    (property "Author" "Antmicro" (at 86.36 132.08 0)
      (effects (font (size 1.27 1.27) (thickness 0.15)) (justify left bottom) hide)
    )
    (pin "1")
    (pin "2")
    (instances
      (project "thunderbolt-pcie-adapter"
        (path ""
          (reference "R19") (unit 1)
        )
      )
    )
  )

  (symbol (lib_id "antmicropower:GND") (at 349.25 76.2 0) (unit 1)
    (in_bom yes) (on_board yes) (dnp no)
    (property "Reference" "#PWR061" (at 349.25 82.55 0)
      (effects (font (size 1.27 1.27)) hide)
    )
    (property "Value" "GND" (at 347.345 80.645 0)
      (effects (font (size 1.27 1.27) (thickness 0.15)) (justify left bottom))
    )
    (property "Footprint" "" (at 349.25 76.2 0)
      (effects (font (size 1.27 1.27) (thickness 0.15)) (justify left bottom) hide)
    )
    (property "Datasheet" "" (at 349.25 76.2 0)
      (effects (font (size 1.27 1.27) (thickness 0.15)) (justify left bottom) hide)
    )
    (property "Author" "Antmicro" (at 358.14 83.82 0)
      (effects (font (size 1.27 1.27) (thickness 0.15)) (justify left bottom) hide)
    )
    (property "License" "Apache-2.0" (at 358.14 86.36 0)
      (effects (font (size 1.27 1.27) (thickness 0.15)) (justify left bottom) hide)
    )
    (pin "1")
    (instances
      (project "thunderbolt-pcie-adapter"
        (path ""
          (reference "#PWR061") (unit 1)
        )
      )
    )
  )

  (symbol (lib_id "antmicropower:GND") (at 53.34 215.9 0) (unit 1)
    (in_bom yes) (on_board yes) (dnp no)
    (property "Reference" "#PWR09" (at 53.34 222.25 0)
      (effects (font (size 1.27 1.27)) hide)
    )
    (property "Value" "GND" (at 51.435 220.345 0)
      (effects (font (size 1.27 1.27) (thickness 0.15)) (justify left bottom))
    )
    (property "Footprint" "" (at 53.34 215.9 0)
      (effects (font (size 1.27 1.27) (thickness 0.15)) (justify left bottom) hide)
    )
    (property "Datasheet" "" (at 53.34 215.9 0)
      (effects (font (size 1.27 1.27) (thickness 0.15)) (justify left bottom) hide)
    )
    (property "Author" "Antmicro" (at 62.23 223.52 0)
      (effects (font (size 1.27 1.27) (thickness 0.15)) (justify left bottom) hide)
    )
    (property "License" "Apache-2.0" (at 62.23 226.06 0)
      (effects (font (size 1.27 1.27) (thickness 0.15)) (justify left bottom) hide)
    )
    (pin "1")
    (instances
      (project "thunderbolt-pcie-adapter"
        (path ""
          (reference "#PWR09") (unit 1)
        )
      )
    )
  )

  (symbol (lib_id "antmicropower:GND") (at 339.09 76.2 0) (unit 1)
    (in_bom yes) (on_board yes) (dnp no)
    (property "Reference" "#PWR054" (at 339.09 82.55 0)
      (effects (font (size 1.27 1.27)) hide)
    )
    (property "Value" "GND" (at 337.185 80.645 0)
      (effects (font (size 1.27 1.27) (thickness 0.15)) (justify left bottom))
    )
    (property "Footprint" "" (at 339.09 76.2 0)
      (effects (font (size 1.27 1.27) (thickness 0.15)) (justify left bottom) hide)
    )
    (property "Datasheet" "" (at 339.09 76.2 0)
      (effects (font (size 1.27 1.27) (thickness 0.15)) (justify left bottom) hide)
    )
    (property "Author" "Antmicro" (at 347.98 83.82 0)
      (effects (font (size 1.27 1.27) (thickness 0.15)) (justify left bottom) hide)
    )
    (property "License" "Apache-2.0" (at 347.98 86.36 0)
      (effects (font (size 1.27 1.27) (thickness 0.15)) (justify left bottom) hide)
    )
    (pin "1")
    (instances
      (project "thunderbolt-pcie-adapter"
        (path ""
          (reference "#PWR054") (unit 1)
        )
      )
    )
  )

  (symbol (lib_id "antmicropower:GND") (at 63.5 215.9 0) (unit 1)
    (in_bom yes) (on_board yes) (dnp no)
    (property "Reference" "#PWR096" (at 63.5 222.25 0)
      (effects (font (size 1.27 1.27)) hide)
    )
    (property "Value" "GND" (at 61.595 220.345 0)
      (effects (font (size 1.27 1.27) (thickness 0.15)) (justify left bottom))
    )
    (property "Footprint" "" (at 63.5 215.9 0)
      (effects (font (size 1.27 1.27) (thickness 0.15)) (justify left bottom) hide)
    )
    (property "Datasheet" "" (at 63.5 215.9 0)
      (effects (font (size 1.27 1.27) (thickness 0.15)) (justify left bottom) hide)
    )
    (property "Author" "Antmicro" (at 72.39 223.52 0)
      (effects (font (size 1.27 1.27) (thickness 0.15)) (justify left bottom) hide)
    )
    (property "License" "Apache-2.0" (at 72.39 226.06 0)
      (effects (font (size 1.27 1.27) (thickness 0.15)) (justify left bottom) hide)
    )
    (pin "1")
    (instances
      (project "thunderbolt-pcie-adapter"
        (path ""
          (reference "#PWR096") (unit 1)
        )
      )
    )
  )

  (symbol (lib_id "antmicroCapacitors0402:C_100n_0402") (at 281.94 50.8 90) (unit 1)
    (in_bom yes) (on_board yes) (dnp no)
    (property "Reference" "C24" (at 282.575 46.355 90)
      (effects (font (size 1.27 1.27) (thickness 0.15)) (justify right))
    )
    (property "Value" "C_100n_0402" (at 292.1 30.48 0)
      (effects (font (size 1.27 1.27) (thickness 0.15)) (justify left bottom) hide)
    )
    (property "Footprint" "antmicro-footprints:C_0402_1005Metric" (at 294.64 30.48 0)
      (effects (font (size 1.27 1.27) (thickness 0.15)) (justify left bottom) hide)
    )
    (property "Datasheet" "https://www.murata.com/products/productdetail?partno=GRM155R61H104KE14%23" (at 297.18 30.48 0)
      (effects (font (size 1.27 1.27) (thickness 0.15)) (justify left bottom) hide)
    )
    (property "MPN" "GRM155R61H104KE14D" (at 299.72 30.48 0)
      (effects (font (size 1.27 1.27) (thickness 0.15)) (justify left bottom) hide)
    )
    (property "Manufacturer" "Murata" (at 302.26 30.48 0)
      (effects (font (size 1.27 1.27) (thickness 0.15)) (justify left bottom) hide)
    )
    (property "License" "Apache-2.0" (at 304.8 30.48 0)
      (effects (font (size 1.27 1.27) (thickness 0.15)) (justify left bottom) hide)
    )
    (property "Val" "100n" (at 287.02 49.53 90)
      (effects (font (size 1.27 1.27) (thickness 0.15)) (justify left bottom))
    )
    (property "Voltage" "50V" (at 309.88 30.48 0)
      (effects (font (size 1.27 1.27)) (justify left bottom) hide)
    )
    (property "Dielectric" "X5R" (at 312.42 30.48 0)
      (effects (font (size 1.27 1.27)) (justify left bottom) hide)
    )
    (property "Author" "Antmicro" (at 307.34 30.48 0)
      (effects (font (size 1.27 1.27) (thickness 0.15)) (justify left bottom) hide)
    )
    (pin "1")
    (pin "2")
    (instances
      (project "thunderbolt-pcie-adapter"
        (path ""
          (reference "C24") (unit 1)
        )
      )
    )
  )

  (symbol (lib_id "antmicroCapacitors0402:C_2u2_0402") (at 135.89 60.96 0) (unit 1)
    (in_bom yes) (on_board yes) (dnp no)
    (property "Reference" "C36" (at 140.97 59.69 0)
      (effects (font (size 1.27 1.27) (thickness 0.15)))
    )
    (property "Value" "C_2u2_0402" (at 156.21 71.12 0)
      (effects (font (size 1.27 1.27) (thickness 0.15)) (justify left bottom) hide)
    )
    (property "Footprint" "antmicro-footprints:C_0402_1005Metric" (at 156.21 73.66 0)
      (effects (font (size 1.27 1.27) (thickness 0.15)) (justify left bottom) hide)
    )
    (property "Datasheet" "https://product.tdk.com/en/search/capacitor/ceramic/mlcc/info?part_no=C1005X5R1A225K050BC" (at 156.21 76.2 0)
      (effects (font (size 1.27 1.27) (thickness 0.15)) (justify left bottom) hide)
    )
    (property "MPN" "C1005X5R1A225K050BC" (at 156.21 78.74 0)
      (effects (font (size 1.27 1.27) (thickness 0.15)) (justify left bottom) hide)
    )
    (property "Manufacturer" "TDK" (at 156.21 81.28 0)
      (effects (font (size 1.27 1.27) (thickness 0.15)) (justify left bottom) hide)
    )
    (property "License" "Apache-2.0" (at 156.21 83.82 0)
      (effects (font (size 1.27 1.27) (thickness 0.15)) (justify left bottom) hide)
    )
    (property "Val" "2u2" (at 139.065 62.865 0)
      (effects (font (size 1.27 1.27) (thickness 0.15)) (justify left bottom))
    )
    (property "Voltage" "" (at 156.21 88.9 0)
      (effects (font (size 1.27 1.27)) (justify left bottom) hide)
    )
    (property "Dielectric" "" (at 156.21 91.44 0)
      (effects (font (size 1.27 1.27)) (justify left bottom) hide)
    )
    (property "Author" "Antmicro" (at 156.21 86.36 0)
      (effects (font (size 1.27 1.27) (thickness 0.15)) (justify left bottom) hide)
    )
    (pin "1")
    (pin "2")
    (instances
      (project "thunderbolt-pcie-adapter"
        (path ""
          (reference "C36") (unit 1)
        )
      )
    )
  )

  (symbol (lib_id "antmicropower:PWR_FLAG") (at 288.29 43.18 0) (unit 1)
    (in_bom yes) (on_board yes) (dnp no)
    (property "Reference" "#FLG0110" (at 288.29 41.275 0)
      (effects (font (size 1.27 1.27)) hide)
    )
    (property "Value" "PWR_FLAG" (at 288.29 39.37 0)
      (effects (font (size 1.27 1.27)))
    )
    (property "Footprint" "" (at 288.29 43.18 0)
      (effects (font (size 1.27 1.27)) hide)
    )
    (property "Datasheet" "" (at 288.29 43.18 0)
      (effects (font (size 1.27 1.27)) hide)
    )
    (pin "1")
    (instances
      (project "thunderbolt-pcie-adapter"
        (path ""
          (reference "#FLG0110") (unit 1)
        )
      )
    )
  )

  (symbol (lib_id "antmicropower:GND") (at 59.69 267.97 0) (unit 1)
    (in_bom yes) (on_board yes) (dnp no)
    (property "Reference" "#PWR0164" (at 59.69 274.32 0)
      (effects (font (size 1.27 1.27)) hide)
    )
    (property "Value" "GND" (at 57.785 272.415 0)
      (effects (font (size 1.27 1.27) (thickness 0.15)) (justify left bottom))
    )
    (property "Footprint" "" (at 59.69 267.97 0)
      (effects (font (size 1.27 1.27) (thickness 0.15)) (justify left bottom) hide)
    )
    (property "Datasheet" "" (at 59.69 267.97 0)
      (effects (font (size 1.27 1.27) (thickness 0.15)) (justify left bottom) hide)
    )
    (property "Author" "Antmicro" (at 68.58 275.59 0)
      (effects (font (size 1.27 1.27) (thickness 0.15)) (justify left bottom) hide)
    )
    (property "License" "Apache-2.0" (at 68.58 278.13 0)
      (effects (font (size 1.27 1.27) (thickness 0.15)) (justify left bottom) hide)
    )
    (pin "1")
    (instances
      (project "thunderbolt-pcie-adapter"
        (path ""
          (reference "#PWR0164") (unit 1)
        )
      )
    )
  )

  (symbol (lib_id "antmicroResistors0402:R_100k_0402") (at 50.8 149.86 0) (unit 1)
    (in_bom yes) (on_board yes) (dnp no)
    (property "Reference" "R9" (at 53.34 147.955 0)
      (effects (font (size 1.27 1.27) (thickness 0.15)))
    )
    (property "Value" "R_100k_0402" (at 71.12 162.56 0)
      (effects (font (size 1.27 1.27) (thickness 0.15)) (justify left bottom) hide)
    )
    (property "Footprint" "antmicro-footprints:R_0402_1005Metric" (at 71.12 165.1 0)
      (effects (font (size 1.27 1.27) (thickness 0.15)) (justify left bottom) hide)
    )
    (property "Datasheet" "https://www.bourns.com/docs/product-datasheets/cr.pdf" (at 71.12 167.64 0)
      (effects (font (size 1.27 1.27) (thickness 0.15)) (justify left bottom) hide)
    )
    (property "MPN" "CR0402-FX-1003GLF" (at 71.12 170.18 0)
      (effects (font (size 1.27 1.27) (thickness 0.15)) (justify left bottom) hide)
    )
    (property "Manufacturer" "Bourns" (at 71.12 172.72 0)
      (effects (font (size 1.27 1.27) (thickness 0.15)) (justify left bottom) hide)
    )
    (property "License" "Apache-2.0" (at 71.12 175.26 0)
      (effects (font (size 1.27 1.27) (thickness 0.15)) (justify left bottom) hide)
    )
    (property "Val" "100k" (at 54.61 148.59 0)
      (effects (font (size 1.27 1.27) (thickness 0.15)) (justify left bottom))
    )
    (property "Tolerance" "1%" (at 71.12 160.02 0)
      (effects (font (size 1.27 1.27)) (justify left bottom) hide)
    )
    (property "Author" "Antmicro" (at 71.12 177.8 0)
      (effects (font (size 1.27 1.27) (thickness 0.15)) (justify left bottom) hide)
    )
    (pin "1")
    (pin "2")
    (instances
      (project "thunderbolt-pcie-adapter"
        (path ""
          (reference "R9") (unit 1)
        )
      )
    )
  )

  (symbol (lib_id "antmicropower:GND") (at 135.89 81.28 90) (unit 1)
    (in_bom yes) (on_board yes) (dnp no)
    (property "Reference" "#PWR029" (at 142.24 81.28 0)
      (effects (font (size 1.27 1.27)) hide)
    )
    (property "Value" "GND" (at 140.335 83.185 0)
      (effects (font (size 1.27 1.27) (thickness 0.15)) (justify left bottom))
    )
    (property "Footprint" "" (at 135.89 81.28 0)
      (effects (font (size 1.27 1.27) (thickness 0.15)) (justify left bottom) hide)
    )
    (property "Datasheet" "" (at 135.89 81.28 0)
      (effects (font (size 1.27 1.27) (thickness 0.15)) (justify left bottom) hide)
    )
    (property "Author" "Antmicro" (at 143.51 72.39 0)
      (effects (font (size 1.27 1.27) (thickness 0.15)) (justify left bottom) hide)
    )
    (property "License" "Apache-2.0" (at 146.05 72.39 0)
      (effects (font (size 1.27 1.27) (thickness 0.15)) (justify left bottom) hide)
    )
    (pin "1")
    (instances
      (project "thunderbolt-pcie-adapter"
        (path ""
          (reference "#PWR029") (unit 1)
        )
      )
    )
  )

  (symbol (lib_id "antmicroShuntsJumpers:Net-Tie_P0.127mm") (at 247.65 214.63 270) (unit 1)
    (in_bom no) (on_board yes) (dnp no)
    (property "Reference" "TP10" (at 248.285 217.805 90)
      (effects (font (size 1.27 1.27) (thickness 0.15)) (justify left))
    )
    (property "Value" "Net-Tie_P0.127mm" (at 249.555 219.075 90)
      (effects (font (size 1.27 1.27) (thickness 0.15)) (justify left) hide)
    )
    (property "Footprint" "antmicro-footprints:NetTie-2_SMD_Pad0.127mm" (at 234.95 236.22 0)
      (effects (font (size 1.27 1.27) (thickness 0.15)) (justify left bottom) hide)
    )
    (property "Datasheet" "" (at 232.41 236.22 0)
      (effects (font (size 1.27 1.27) (thickness 0.15)) (justify left bottom) hide)
    )
    (property "MPN" "" (at 237.49 236.22 0)
      (effects (font (size 1.27 1.27) (thickness 0.15)) (justify left bottom))
    )
    (property "Manufacturer" "" (at 229.87 236.22 0)
      (effects (font (size 1.27 1.27) (thickness 0.15)) (justify left bottom) hide)
    )
    (property "Author" "Antmicro" (at 227.33 236.22 0)
      (effects (font (size 1.27 1.27) (thickness 0.15)) (justify left bottom) hide)
    )
    (property "License" "Apache-2.0" (at 224.79 236.22 0)
      (effects (font (size 1.27 1.27) (thickness 0.15)) (justify left bottom) hide)
    )
    (pin "1")
    (pin "2")
    (instances
      (project "thunderbolt-pcie-adapter"
        (path ""
          (reference "TP10") (unit 1)
        )
      )
    )
  )

  (symbol (lib_id "antmicropower:GND") (at 358.14 171.45 0) (unit 1)
    (in_bom yes) (on_board yes) (dnp no)
    (property "Reference" "#PWR0154" (at 358.14 177.8 0)
      (effects (font (size 1.27 1.27)) hide)
    )
    (property "Value" "GND" (at 356.235 175.895 0)
      (effects (font (size 1.27 1.27) (thickness 0.15)) (justify left bottom))
    )
    (property "Footprint" "" (at 358.14 171.45 0)
      (effects (font (size 1.27 1.27) (thickness 0.15)) (justify left bottom) hide)
    )
    (property "Datasheet" "" (at 358.14 171.45 0)
      (effects (font (size 1.27 1.27) (thickness 0.15)) (justify left bottom) hide)
    )
    (property "Author" "Antmicro" (at 367.03 179.07 0)
      (effects (font (size 1.27 1.27) (thickness 0.15)) (justify left bottom) hide)
    )
    (property "License" "Apache-2.0" (at 367.03 181.61 0)
      (effects (font (size 1.27 1.27) (thickness 0.15)) (justify left bottom) hide)
    )
    (pin "1")
    (instances
      (project "thunderbolt-pcie-adapter"
        (path ""
          (reference "#PWR0154") (unit 1)
        )
      )
    )
  )

  (symbol (lib_id "antmicroResistors0402:R_10k_0402") (at 29.21 64.77 90) (unit 1)
    (in_bom yes) (on_board yes) (dnp no)
    (property "Reference" "R2" (at 30.48 60.96 90)
      (effects (font (size 1.27 1.27) (thickness 0.15)) (justify right))
    )
    (property "Value" "R_10k_0402" (at 41.91 44.45 0)
      (effects (font (size 1.27 1.27) (thickness 0.15)) (justify left bottom) hide)
    )
    (property "Footprint" "antmicro-footprints:R_0402_1005Metric" (at 44.45 44.45 0)
      (effects (font (size 1.27 1.27) (thickness 0.15)) (justify left bottom) hide)
    )
    (property "Datasheet" "https://www.bourns.com/docs/product-datasheets/cr.pdf" (at 46.99 44.45 0)
      (effects (font (size 1.27 1.27) (thickness 0.15)) (justify left bottom) hide)
    )
    (property "MPN" "CR0402-FX-1002GLF" (at 49.53 44.45 0)
      (effects (font (size 1.27 1.27) (thickness 0.15)) (justify left bottom) hide)
    )
    (property "Manufacturer" "Bourns" (at 52.07 44.45 0)
      (effects (font (size 1.27 1.27) (thickness 0.15)) (justify left bottom) hide)
    )
    (property "License" "Apache-2.0" (at 54.61 44.45 0)
      (effects (font (size 1.27 1.27) (thickness 0.15)) (justify left bottom) hide)
    )
    (property "Val" "10k" (at 33.655 62.23 90)
      (effects (font (size 1.27 1.27) (thickness 0.15)) (justify left bottom))
    )
    (property "Tolerance" "1%" (at 39.37 44.45 0)
      (effects (font (size 1.27 1.27)) (justify left bottom) hide)
    )
    (property "Author" "Antmicro" (at 57.15 44.45 0)
      (effects (font (size 1.27 1.27) (thickness 0.15)) (justify left bottom) hide)
    )
    (pin "1")
    (pin "2")
    (instances
      (project "thunderbolt-pcie-adapter"
        (path ""
          (reference "R2") (unit 1)
        )
      )
    )
  )

  (symbol (lib_id "antmicropower:GND") (at 251.46 171.45 0) (unit 1)
    (in_bom yes) (on_board yes) (dnp no)
    (property "Reference" "#PWR0158" (at 251.46 177.8 0)
      (effects (font (size 1.27 1.27)) hide)
    )
    (property "Value" "GND" (at 249.555 175.895 0)
      (effects (font (size 1.27 1.27) (thickness 0.15)) (justify left bottom))
    )
    (property "Footprint" "" (at 251.46 171.45 0)
      (effects (font (size 1.27 1.27) (thickness 0.15)) (justify left bottom) hide)
    )
    (property "Datasheet" "" (at 251.46 171.45 0)
      (effects (font (size 1.27 1.27) (thickness 0.15)) (justify left bottom) hide)
    )
    (property "Author" "Antmicro" (at 260.35 179.07 0)
      (effects (font (size 1.27 1.27) (thickness 0.15)) (justify left bottom) hide)
    )
    (property "License" "Apache-2.0" (at 260.35 181.61 0)
      (effects (font (size 1.27 1.27) (thickness 0.15)) (justify left bottom) hide)
    )
    (pin "1")
    (instances
      (project "thunderbolt-pcie-adapter"
        (path ""
          (reference "#PWR0158") (unit 1)
        )
      )
    )
  )

  (symbol (lib_id "antmicropower:GND") (at 62.23 63.5 0) (unit 1)
    (in_bom yes) (on_board yes) (dnp no)
    (property "Reference" "#PWR020" (at 62.23 69.85 0)
      (effects (font (size 1.27 1.27)) hide)
    )
    (property "Value" "GND" (at 55.88 66.04 0)
      (effects (font (size 1.27 1.27) (thickness 0.15)) (justify left bottom))
    )
    (property "Footprint" "" (at 62.23 63.5 0)
      (effects (font (size 1.27 1.27) (thickness 0.15)) (justify left bottom) hide)
    )
    (property "Datasheet" "" (at 62.23 63.5 0)
      (effects (font (size 1.27 1.27) (thickness 0.15)) (justify left bottom) hide)
    )
    (property "Author" "Antmicro" (at 71.12 71.12 0)
      (effects (font (size 1.27 1.27) (thickness 0.15)) (justify left bottom) hide)
    )
    (property "License" "Apache-2.0" (at 71.12 73.66 0)
      (effects (font (size 1.27 1.27) (thickness 0.15)) (justify left bottom) hide)
    )
    (pin "1")
    (instances
      (project "thunderbolt-pcie-adapter"
        (path ""
          (reference "#PWR020") (unit 1)
        )
      )
    )
  )

  (symbol (lib_id "antmicropower:GND") (at 50.8 149.86 270) (unit 1)
    (in_bom yes) (on_board yes) (dnp no)
    (property "Reference" "#PWR014" (at 44.45 149.86 0)
      (effects (font (size 1.27 1.27)) hide)
    )
    (property "Value" "GND" (at 46.99 147.955 0)
      (effects (font (size 1.27 1.27) (thickness 0.15)) (justify left bottom))
    )
    (property "Footprint" "" (at 50.8 149.86 0)
      (effects (font (size 1.27 1.27) (thickness 0.15)) (justify left bottom) hide)
    )
    (property "Datasheet" "" (at 50.8 149.86 0)
      (effects (font (size 1.27 1.27) (thickness 0.15)) (justify left bottom) hide)
    )
    (property "Author" "Antmicro" (at 43.18 158.75 0)
      (effects (font (size 1.27 1.27) (thickness 0.15)) (justify left bottom) hide)
    )
    (property "License" "Apache-2.0" (at 40.64 158.75 0)
      (effects (font (size 1.27 1.27) (thickness 0.15)) (justify left bottom) hide)
    )
    (pin "1")
    (instances
      (project "thunderbolt-pcie-adapter"
        (path ""
          (reference "#PWR014") (unit 1)
        )
      )
    )
  )
)
